FILE_TYPE = MACRO_DRAWING;
SET COLOR_WIRE YELLOW;
SET COLOR_PROP MONO;
SET COLOR_DOT WHITE;
SET COLOR_ARC YELLOW;
SET COLOR_BODY GREEN;
SET COLOR_NOTE MONO;
SET PROP_DISPLAY VALUE;
SET PAGE_NUMBER P194;
FORCEADD GND..1
(-1900 2925);
FORCEPROP 3 LASTPIN (-1900 2975) SIG_NAME GND\g
J 0
(-1890 2985);
DISPLAY 0.659574 (-1890 2985);
PAINT MONO (-1890 2985);
DISPLAY INVISIBLE (-1890 2985);
FORCEPROP 1 LAST VOLTAGE 0
J 0
(-1900 2925);
PAINT SKYBLUE (-1900 2925);
DISPLAY INVISIBLE (-1900 2925);
FORCEPROP 2 LAST CDS_LIB mstr_symbols
J 0
(-1900 2925);
PAINT ORANGE (-1900 2925);
DISPLAY INVISIBLE (-1900 2925);
FORCEPROP 2 LAST BOM_COST PROC_VRD_VCCIN_CPU0
J 0
(-2275 3000);
DISPLAY 1.446809 (-2275 3000);
PAINT MONO (-2275 3000);
DISPLAY INVISIBLE (-2275 3000);
FORCEPROP 1 LAST SIZE 1B
J 0
(-1825 2875);
DISPLAY 1.723404 (-1825 2875);
PAINT GREEN (-1825 2875);
DISPLAY INVISIBLE (-1825 2875);
FORCEPROP 1 LAST PATH I100
J 0
(-1825 2925);
DISPLAY 0.872340 (-1825 2925);
PAINT AQUA (-1825 2925);
DISPLAY INVISIBLE (-1825 2925);
FORCEPROP 2 LAST ROOM PVSA_CPU0_DECAP_VR
J 0
(-2450 3000);
DISPLAY 1.936170 (-2450 3000);
PAINT ORANGE (-2450 3000);
DISPLAY INVISIBLE (-2450 3000);
FORCEPROP 1 LAST BODY_TYPE PLUMBING
J 0
(-1945 2882);
DISPLAY 0.340426 (-1945 2882);
PAINT GREEN (-1945 2882);
DISPLAY INVISIBLE (-1945 2882);
FORCEPROP 1 LAST HDL_POWER GND
J 0
(-1900 3075);
DISPLAY 1.723404 (-1900 3075);
PAINT GREEN (-1900 3075);
DISPLAY INVISIBLE (-1900 3075);
FORCEADD CAPP..1
(-1900 3100);
FORCEPROP 0 LAST GROUP PWR_MCP_CAP
J 0
(-1850 2850);
DISPLAY 0.638298 (-1850 2850);
PAINT BROWN (-1850 2850);
DISPLAY BOTH (-1850 2850);
FORCEPROP 1 LAST PART_NUMBER 699013-049
J 0
(-1850 2900);
DISPLAY 0.617021 (-1850 2900);
PAINT BLUE (-1850 2900);
FORCEPROP 1 LAST VALUE 470UF
J 0
(-1850 3150);
DISPLAY 0.617021 (-1850 3150);
PAINT SKYBLUE (-1850 3150);
FORCEPROP 1 LAST LOCATION C3N14
J 0
(-1850 3200);
DISPLAY 0.617021 (-1850 3200);
PAINT AQUA (-1850 3200);
FORCEPROP 1 LASTPIN (-1900 3000) $PN 2
J 0
(-1890 2985);
DISPLAY 0.617021 (-1890 2985);
PAINT ORANGE (-1890 2985);
FORCEPROP 1 LASTPIN (-1900 3200) $PN 1
J 0
(-1890 3185);
DISPLAY 0.617021 (-1890 3185);
PAINT ORANGE (-1890 3185);
FORCEPROP 1 LAST TOLERANCE 20%
J 0
(-1850 3100);
DISPLAY 0.617021 (-1850 3100);
PAINT SKYBLUE (-1850 3100);
FORCEPROP 1 LAST VOLTAGE 2.5V
J 0
(-1850 3050);
DISPLAY 0.638298 (-1850 3050);
PAINT SKYBLUE (-1850 3050);
FORCEPROP 1 LAST MATERIAL ALUM
J 0
(-1850 3000);
DISPLAY 0.617021 (-1850 3000);
PAINT SKYBLUE (-1850 3000);
FORCEPROP 1 LAST PACK_TYPE 3018
J 0
(-1850 2950);
DISPLAY 0.617021 (-1850 2950);
PAINT SKYBLUE (-1850 2950);
FORCEPROP 2 LAST SEC_TYPE 3018
J 0
(-1850 3300);
DISPLAY 1.021277 (-1850 3300);
PAINT ORANGE (-1850 3300);
DISPLAY INVISIBLE (-1850 3300);
FORCEPROP 2 LAST CDS_LIB mstr_discrete
J 0
(-1900 3100);
PAINT ORANGE (-1900 3100);
DISPLAY INVISIBLE (-1900 3100);
FORCEPROP 2 LAST BOM_COST PROC_VRD_VCCIN_CPU0
J 0
(-1850 3250);
PAINT MONO (-1850 3250);
DISPLAY INVISIBLE (-1850 3250);
FORCEPROP 2 LAST SEC 1
J 0
(-1850 3300);
PAINT MONO (-1850 3300);
DISPLAY INVISIBLE (-1850 3300);
FORCEPROP 2 LAST CDS_LOCATION C3N14
J 0
(-1850 3200);
DISPLAY 0.617021 (-1850 3200);
PAINT AQUA (-1850 3200);
DISPLAY INVISIBLE (-1850 3200);
FORCEPROP 1 LAST PATH I101
J 0
(-1850 3250);
DISPLAY 0.978723 (-1850 3250);
PAINT ORANGE (-1850 3250);
DISPLAY INVISIBLE (-1850 3250);
FORCEPROP 2 LAST ROOM P0V95_MCP_CPU0_DECAP_VR
J 0
(-1850 3225);
PAINT MONO (-1850 3225);
DISPLAY INVISIBLE (-1850 3225);
FORCEADD VCC_CORE..1
(-1900 3275);
FORCEPROP 3 LASTPIN (-1900 3225) SIG_NAME PVCCIOMCP_CPU0\g
J 0
(-1890 3235);
DISPLAY 0.659574 (-1890 3235);
PAINT MONO (-1890 3235);
DISPLAY INVISIBLE (-1890 3235);
FORCEPROP 1 LAST HDL_POWER PVCCIOMCP_CPU0
J 1
(-1900 3325);
DISPLAY 0.617021 (-1900 3325);
PAINT GREEN (-1900 3325);
FORCEPROP 0 LAST VOLTAGE +0.95
J 0
(-1900 3425);
DISPLAY 1.021277 (-1900 3425);
PAINT SKYBLUE (-1900 3425);
DISPLAY INVISIBLE (-1900 3425);
FORCEPROP 2 LAST CDS_LIB mstr_symbols
J 0
(-1900 3275);
PAINT ORANGE (-1900 3275);
DISPLAY INVISIBLE (-1900 3275);
FORCEPROP 1 LAST PATH I102
J 0
(-1850 3300);
DISPLAY 0.872340 (-1850 3300);
PAINT AQUA (-1850 3300);
DISPLAY INVISIBLE (-1850 3300);
FORCEADD GND..1
(-7375 1225);
FORCEPROP 3 LASTPIN (-7375 1275) SIG_NAME GND\g
J 0
(-7365 1285);
DISPLAY 0.659574 (-7365 1285);
PAINT MONO (-7365 1285);
DISPLAY INVISIBLE (-7365 1285);
FORCEPROP 1 LAST PATH I110
J 0
(-7300 1225);
DISPLAY 0.872340 (-7300 1225);
PAINT AQUA (-7300 1225);
DISPLAY INVISIBLE (-7300 1225);
FORCEPROP 2 LAST CDS_LIB mstr_symbols
J 0
(-7375 1225);
PAINT MONO (-7375 1225);
DISPLAY INVISIBLE (-7375 1225);
FORCEPROP 1 LAST SIZE 1B
J 0
(-7300 1175);
DISPLAY 1.404255 (-7300 1175);
PAINT AQUA (-7300 1175);
DISPLAY INVISIBLE (-7300 1175);
FORCEPROP 1 LAST VOLTAGE 0.0V
J 0
(-7420 1182);
DISPLAY 0.340426 (-7420 1182);
PAINT SKYBLUE (-7420 1182);
DISPLAY INVISIBLE (-7420 1182);
FORCEPROP 1 LAST BODY_TYPE PLUMBING
J 0
(-7420 1182);
DISPLAY 0.340426 (-7420 1182);
PAINT GREEN (-7420 1182);
DISPLAY INVISIBLE (-7420 1182);
FORCEPROP 1 LAST HDL_POWER GND
J 0
(-7375 1375);
PAINT GREEN (-7375 1375);
DISPLAY INVISIBLE (-7375 1375);
FORCEADD GND..1
(-7225 675);
FORCEPROP 3 LASTPIN (-7225 725) SIG_NAME GND\g
J 0
(-7215 735);
DISPLAY 0.659574 (-7215 735);
PAINT MONO (-7215 735);
DISPLAY INVISIBLE (-7215 735);
FORCEPROP 1 LAST PATH I111
J 0
(-7150 675);
DISPLAY 0.872340 (-7150 675);
PAINT AQUA (-7150 675);
DISPLAY INVISIBLE (-7150 675);
FORCEPROP 1 LAST SIZE 1B
J 0
(-7150 625);
DISPLAY 1.404255 (-7150 625);
PAINT AQUA (-7150 625);
DISPLAY INVISIBLE (-7150 625);
FORCEPROP 2 LAST CDS_LIB mstr_symbols
J 0
(-7225 675);
PAINT MONO (-7225 675);
DISPLAY INVISIBLE (-7225 675);
FORCEPROP 1 LAST VOLTAGE 0.0V
J 0
(-7270 632);
DISPLAY 0.340426 (-7270 632);
PAINT SKYBLUE (-7270 632);
DISPLAY INVISIBLE (-7270 632);
FORCEPROP 1 LAST BODY_TYPE PLUMBING
J 0
(-7270 632);
DISPLAY 0.340426 (-7270 632);
PAINT GREEN (-7270 632);
DISPLAY INVISIBLE (-7270 632);
FORCEPROP 1 LAST HDL_POWER GND
J 0
(-7225 825);
PAINT GREEN (-7225 825);
DISPLAY INVISIBLE (-7225 825);
FORCEADD OFFPAGE..4
(-5275 625);
FORCEPROP 2 LAST $XR2 211 
J 0
(-4879 625);
DISPLAY 0.638298 (-4879 625);
PAINT MONO (-4879 625);
FORCEPROP 2 LAST $XR1 201 
J 0
(-4999 625);
DISPLAY 0.638298 (-4999 625);
PAINT MONO (-4999 625);
FORCEPROP 2 LAST $XR0 21 
J 0
(-5089 625);
DISPLAY 0.638298 (-5089 625);
PAINT MONO (-5089 625);
FORCEPROP 2 LAST PATH I114
J 0
(-5100 700);
DISPLAY 1.021277 (-5100 700);
PAINT ORANGE (-5100 700);
DISPLAY INVISIBLE (-5100 700);
FORCEPROP 2 LAST ROOM P0V95_FPGA_CPU0_VR
J 0
(-5825 700);
DISPLAY 1.361702 (-5825 700);
PAINT ORANGE (-5825 700);
DISPLAY INVISIBLE (-5825 700);
FORCEPROP 2 LAST CDS_LIB mstr_standard
J 0
(-5275 625);
PAINT MONO (-5275 625);
DISPLAY INVISIBLE (-5275 625);
FORCEPROP 1 LAST OFFPAGE TRUE
J 0
(-4950 500);
DISPLAY 0.872340 (-4950 500);
PAINT GREEN (-4950 500);
DISPLAY INVISIBLE (-4950 500);
FORCEPROP 1 LAST COMMENT_BODY TRUE
J 0
(-5300 525);
DISPLAY 0.872340 (-5300 525);
PAINT GREEN (-5300 525);
DISPLAY INVISIBLE (-5300 525);
FORCEADD OFFPAGE..1
R 2
(-5300 1325);
FORCEPROP 2 LAST $XR5 193 
J 0
(-4514 1325);
DISPLAY 0.638298 (-4514 1325);
PAINT MONO (-4514 1325);
FORCEPROP 2 LAST $XR6 201 
J 0
(-4394 1325);
DISPLAY 0.638298 (-4394 1325);
PAINT MONO (-4394 1325);
FORCEPROP 2 LAST $XR11 226 
J 0
(-4754 1289);
DISPLAY 0.638298 (-4754 1289);
PAINT MONO (-4754 1289);
FORCEPROP 2 LAST $XR10 223 
J 0
(-4874 1289);
DISPLAY 0.638298 (-4874 1289);
PAINT MONO (-4874 1289);
FORCEPROP 2 LAST $XR9 218 
J 0
(-4994 1289);
DISPLAY 0.638298 (-4994 1289);
PAINT MONO (-4994 1289);
FORCEPROP 2 LAST $XR8 215 
J 0
(-4154 1325);
DISPLAY 0.638298 (-4154 1325);
PAINT MONO (-4154 1325);
FORCEPROP 2 LAST $XR7 206 
J 0
(-4274 1325);
DISPLAY 0.638298 (-4274 1325);
PAINT MONO (-4274 1325);
FORCEPROP 2 LAST $XR4 235 
J 0
(-4634 1325);
DISPLAY 0.638298 (-4634 1325);
PAINT MONO (-4634 1325);
FORCEPROP 2 LAST $XR3 213 
J 0
(-4754 1325);
DISPLAY 0.638298 (-4754 1325);
PAINT MONO (-4754 1325);
FORCEPROP 2 LAST $XR2 211 
J 0
(-4874 1325);
DISPLAY 0.638298 (-4874 1325);
PAINT MONO (-4874 1325);
FORCEPROP 2 LAST $XR1 159 
J 0
(-4994 1325);
DISPLAY 0.638298 (-4994 1325);
PAINT MONO (-4994 1325);
FORCEPROP 2 LAST $XR0 138 
J 0
(-5114 1325);
DISPLAY 0.638298 (-5114 1325);
PAINT MONO (-5114 1325);
FORCEPROP 2 LAST PATH I116
J 0
(-4625 1400);
DISPLAY 1.021277 (-4625 1400);
PAINT ORANGE (-4625 1400);
DISPLAY INVISIBLE (-4625 1400);
FORCEPROP 2 LAST ROOM P0V95_FPGA_CPU0_VR
J 0
(-5725 1400);
DISPLAY 1.361702 (-5725 1400);
PAINT ORANGE (-5725 1400);
DISPLAY INVISIBLE (-5725 1400);
FORCEPROP 2 LAST CDS_LIB mstr_standard
J 0
(-5300 1325);
PAINT ORANGE (-5300 1325);
DISPLAY INVISIBLE (-5300 1325);
FORCEPROP 1 LAST OFFPAGE TRUE
J 2
(-5625 1200);
DISPLAY 1.170213 (-5625 1200);
PAINT GREEN (-5625 1200);
DISPLAY INVISIBLE (-5625 1200);
FORCEPROP 1 LAST COMMENT_BODY TRUE
J 2
(-5425 1225);
DISPLAY 1.170213 (-5425 1225);
PAINT GREEN (-5425 1225);
DISPLAY INVISIBLE (-5425 1225);
FORCEADD P12V_STBY..1
(-7175 4075);
FORCEPROP 3 LASTPIN (-7175 4025) SIG_NAME P12V_STBY\g
J 0
(-7165 4035);
DISPLAY 0.659574 (-7165 4035);
PAINT MONO (-7165 4035);
DISPLAY INVISIBLE (-7165 4035);
FORCEPROP 1 LAST PATH I119
J 0
(-7130 4077);
DISPLAY 0.340426 (-7130 4077);
PAINT GREEN (-7130 4077);
DISPLAY INVISIBLE (-7130 4077);
FORCEPROP 2 LAST CDS_LIB mstr_symbols
J 0
(-7175 4075);
PAINT MONO (-7175 4075);
DISPLAY INVISIBLE (-7175 4075);
FORCEPROP 1 LAST SIZE 1B
J 0
(-7130 4097);
DISPLAY 0.340426 (-7130 4097);
PAINT GREEN (-7130 4097);
DISPLAY INVISIBLE (-7130 4097);
FORCEPROP 1 LAST VOLTAGE 12.0V
J 0
(-7220 4032);
DISPLAY 0.340426 (-7220 4032);
PAINT SKYBLUE (-7220 4032);
DISPLAY INVISIBLE (-7220 4032);
FORCEPROP 1 LAST BODY_TYPE PLUMBING
J 0
(-7220 4032);
DISPLAY 0.340426 (-7220 4032);
PAINT GREEN (-7220 4032);
DISPLAY INVISIBLE (-7220 4032);
FORCEPROP 1 LAST HDL_POWER P12V_STBY
J 0
(-7475 3950);
DISPLAY 0.872340 (-7475 3950);
PAINT ORANGE (-7475 3950);
DISPLAY INVISIBLE (-7475 3950);
FORCEADD P3V3_STBY..1
(-5725 3900);
FORCEPROP 3 LASTPIN (-5725 3850) SIG_NAME P3V3_STBY\g
J 0
(-5715 3860);
DISPLAY 0.659574 (-5715 3860);
PAINT MONO (-5715 3860);
DISPLAY INVISIBLE (-5715 3860);
FORCEPROP 1 LAST PATH I120
J 0
(-5680 3902);
DISPLAY 0.340426 (-5680 3902);
PAINT GREEN (-5680 3902);
DISPLAY INVISIBLE (-5680 3902);
FORCEPROP 2 LAST CDS_LIB mstr_symbols
J 0
(-5725 3900);
PAINT MONO (-5725 3900);
DISPLAY INVISIBLE (-5725 3900);
FORCEPROP 1 LAST SIZE 1B
J 0
(-5680 3922);
DISPLAY 0.340426 (-5680 3922);
PAINT GREEN (-5680 3922);
DISPLAY INVISIBLE (-5680 3922);
FORCEPROP 1 LAST VOLTAGE +3.3V
J 0
(-5525 4050);
DISPLAY 1.021277 (-5525 4050);
PAINT SKYBLUE (-5525 4050);
DISPLAY INVISIBLE (-5525 4050);
FORCEPROP 1 LAST BODY_TYPE PLUMBING
J 0
(-5770 3857);
DISPLAY 0.340426 (-5770 3857);
PAINT GREEN (-5770 3857);
DISPLAY INVISIBLE (-5770 3857);
FORCEPROP 1 LAST HDL_POWER P3V3_STBY
J 0
(-6025 3775);
DISPLAY 0.872340 (-6025 3775);
PAINT ORANGE (-6025 3775);
DISPLAY INVISIBLE (-6025 3775);
FORCEADD P5V_STBY..1
(-5775 3200);
FORCEPROP 3 LASTPIN (-5775 3150) SIG_NAME P5V_STBY\g
J 0
(-5765 3160);
DISPLAY 0.659574 (-5765 3160);
PAINT MONO (-5765 3160);
DISPLAY INVISIBLE (-5765 3160);
FORCEPROP 1 LAST PATH I121
J 0
(-5730 3202);
DISPLAY 0.340426 (-5730 3202);
PAINT GREEN (-5730 3202);
DISPLAY INVISIBLE (-5730 3202);
FORCEPROP 2 LAST CDS_LIB mstr_symbols
J 0
(-5775 3200);
PAINT MONO (-5775 3200);
DISPLAY INVISIBLE (-5775 3200);
FORCEPROP 1 LAST SIZE 1B
J 0
(-5730 3222);
DISPLAY 0.340426 (-5730 3222);
PAINT GREEN (-5730 3222);
DISPLAY INVISIBLE (-5730 3222);
FORCEPROP 1 LAST VOLTAGE +5.0V
J 0
(-5575 3350);
DISPLAY 1.021277 (-5575 3350);
PAINT SKYBLUE (-5575 3350);
DISPLAY INVISIBLE (-5575 3350);
FORCEPROP 1 LAST BODY_TYPE PLUMBING
J 0
(-5820 3157);
DISPLAY 0.340426 (-5820 3157);
PAINT GREEN (-5820 3157);
DISPLAY INVISIBLE (-5820 3157);
FORCEPROP 1 LAST HDL_POWER P5V_STBY
J 0
(-6075 3075);
DISPLAY 0.872340 (-6075 3075);
PAINT ORANGE (-6075 3075);
DISPLAY INVISIBLE (-6075 3075);
FORCEADD OFFPAGE..3
(-5300 1275);
FORCEPROP 2 LAST $XR9 223 
J 0
(-4126 1239);
DISPLAY 0.638298 (-4126 1239);
PAINT MONO (-4126 1239);
FORCEPROP 2 LAST $XR8 218 
J 0
(-4246 1239);
DISPLAY 0.638298 (-4246 1239);
PAINT MONO (-4246 1239);
FORCEPROP 2 LAST $XR7 215 
J 0
(-4366 1239);
DISPLAY 0.638298 (-4366 1239);
PAINT MONO (-4366 1239);
FORCEPROP 2 LAST $XR11 235 
J 0
(-4486 1275);
DISPLAY 0.638298 (-4486 1275);
PAINT MONO (-4486 1275);
FORCEPROP 2 LAST $XR10 226 
J 0
(-4606 1275);
DISPLAY 0.638298 (-4606 1275);
PAINT MONO (-4606 1275);
FORCEPROP 2 LAST $XR6 213 
J 0
(-4486 1239);
DISPLAY 0.638298 (-4486 1239);
PAINT MONO (-4486 1239);
FORCEPROP 2 LAST $XR5 211 
J 0
(-4606 1239);
DISPLAY 0.638298 (-4606 1239);
PAINT MONO (-4606 1239);
FORCEPROP 2 LAST $XR4 206 
J 0
(-4726 1239);
DISPLAY 0.638298 (-4726 1239);
PAINT MONO (-4726 1239);
FORCEPROP 2 LAST $XR3 201 
J 0
(-4846 1239);
DISPLAY 0.638298 (-4846 1239);
PAINT MONO (-4846 1239);
FORCEPROP 2 LAST $XR1 159 
J 0
(-5086 1239);
DISPLAY 0.638298 (-5086 1239);
PAINT MONO (-5086 1239);
FORCEPROP 2 LAST $XR0 138 
J 0
(-5086 1275);
DISPLAY 0.638298 (-5086 1275);
PAINT MONO (-5086 1275);
FORCEPROP 2 LAST $XR2 193 
J 0
(-4966 1239);
DISPLAY 0.638298 (-4966 1239);
PAINT MONO (-4966 1239);
FORCEPROP 2 LAST PATH I123
J 0
(-5100 1350);
DISPLAY 1.021277 (-5100 1350);
PAINT ORANGE (-5100 1350);
DISPLAY INVISIBLE (-5100 1350);
FORCEPROP 2 LAST ROOM P0V95_FPGA_CPU0_VR
J 0
(-5700 1350);
DISPLAY 1.361702 (-5700 1350);
PAINT ORANGE (-5700 1350);
DISPLAY INVISIBLE (-5700 1350);
FORCEPROP 2 LAST CDS_LIB mstr_standard
J 0
(-5300 1275);
PAINT MONO (-5300 1275);
DISPLAY INVISIBLE (-5300 1275);
FORCEPROP 1 LAST OFFPAGE TRUE
J 0
(-4975 1150);
DISPLAY 1.170213 (-4975 1150);
PAINT GREEN (-4975 1150);
DISPLAY INVISIBLE (-4975 1150);
FORCEPROP 1 LAST COMMENT_BODY TRUE
J 0
(-5350 1175);
DISPLAY 1.170213 (-5350 1175);
PAINT GREEN (-5350 1175);
DISPLAY INVISIBLE (-5350 1175);
FORCEADD OFFPAGE..1
(-8000 1125);
FORCEPROP 2 LAST $XR0 39 
J 0
(-8221 1125);
DISPLAY 0.638298 (-8221 1125);
PAINT MONO (-8221 1125);
FORCEPROP 2 LAST PATH I124
J 0
(-7950 1200);
DISPLAY 1.021277 (-7950 1200);
PAINT ORANGE (-7950 1200);
DISPLAY INVISIBLE (-7950 1200);
FORCEPROP 2 LAST BOM_COST PROC_VRD_VCCIN_CPU0
J 0
(-7675 1175);
PAINT MONO (-7675 1175);
DISPLAY INVISIBLE (-7675 1175);
FORCEPROP 2 LAST CDS_LIB mstr_standard
J 0
(-8000 1125);
PAINT MONO (-8000 1125);
DISPLAY INVISIBLE (-8000 1125);
FORCEPROP 2 LAST ROOM PVSA_CPU0_VSENSE_VR
J 0
(-8400 1200);
PAINT ORANGE (-8400 1200);
DISPLAY INVISIBLE (-8400 1200);
FORCEPROP 1 LAST OFFPAGE TRUE
J 0
(-7675 1000);
DISPLAY 0.872340 (-7675 1000);
PAINT GREEN (-7675 1000);
DISPLAY INVISIBLE (-7675 1000);
FORCEPROP 1 LAST COMMENT_BODY TRUE
J 0
(-7875 1025);
DISPLAY 0.872340 (-7875 1025);
PAINT GREEN (-7875 1025);
DISPLAY INVISIBLE (-7875 1025);
FORCEADD OFFPAGE..1
(-8000 1075);
FORCEPROP 2 LAST $XR0 39 
J 0
(-8221 1075);
DISPLAY 0.638298 (-8221 1075);
PAINT MONO (-8221 1075);
FORCEPROP 2 LAST PATH I125
J 0
(-7950 1150);
DISPLAY 1.021277 (-7950 1150);
PAINT ORANGE (-7950 1150);
DISPLAY INVISIBLE (-7950 1150);
FORCEPROP 2 LAST BOM_COST PROC_VRD_VCCIN_CPU0
J 0
(-7675 1125);
PAINT MONO (-7675 1125);
DISPLAY INVISIBLE (-7675 1125);
FORCEPROP 2 LAST CDS_LIB mstr_standard
J 0
(-8000 1075);
PAINT MONO (-8000 1075);
DISPLAY INVISIBLE (-8000 1075);
FORCEPROP 2 LAST ROOM PVSA_CPU0_VSENSE_VR
J 0
(-8400 1150);
PAINT ORANGE (-8400 1150);
DISPLAY INVISIBLE (-8400 1150);
FORCEPROP 1 LAST OFFPAGE TRUE
J 0
(-7675 950);
DISPLAY 0.872340 (-7675 950);
PAINT GREEN (-7675 950);
DISPLAY INVISIBLE (-7675 950);
FORCEPROP 1 LAST COMMENT_BODY TRUE
J 0
(-7875 975);
DISPLAY 0.872340 (-7875 975);
PAINT GREEN (-7875 975);
DISPLAY INVISIBLE (-7875 975);
FORCEADD GND..1
(-5350 1525);
FORCEPROP 3 LASTPIN (-5350 1575) SIG_NAME GND\g
J 0
(-5340 1585);
DISPLAY 0.659574 (-5340 1585);
PAINT MONO (-5340 1585);
DISPLAY INVISIBLE (-5340 1585);
FORCEPROP 1 LAST PATH I127
J 0
(-5275 1525);
DISPLAY 0.872340 (-5275 1525);
PAINT AQUA (-5275 1525);
DISPLAY INVISIBLE (-5275 1525);
FORCEPROP 1 LAST SIZE 1B
J 0
(-5275 1475);
DISPLAY 1.404255 (-5275 1475);
PAINT AQUA (-5275 1475);
DISPLAY INVISIBLE (-5275 1475);
FORCEPROP 2 LAST CDS_LIB mstr_symbols
J 0
(-5350 1525);
PAINT MONO (-5350 1525);
DISPLAY INVISIBLE (-5350 1525);
FORCEPROP 1 LAST VOLTAGE 0.0V
J 0
(-5395 1482);
DISPLAY 0.340426 (-5395 1482);
PAINT SKYBLUE (-5395 1482);
DISPLAY INVISIBLE (-5395 1482);
FORCEPROP 1 LAST BODY_TYPE PLUMBING
J 0
(-5395 1482);
DISPLAY 0.340426 (-5395 1482);
PAINT GREEN (-5395 1482);
DISPLAY INVISIBLE (-5395 1482);
FORCEPROP 1 LAST HDL_POWER GND
J 0
(-5350 1675);
PAINT GREEN (-5350 1675);
DISPLAY INVISIBLE (-5350 1675);
FORCEADD VCC_CORE..1
(-3900 3925);
FORCEPROP 3 LASTPIN (-3900 3875) SIG_NAME PVCCMCP_CPU0\g
J 0
(-3890 3885);
DISPLAY 0.659574 (-3890 3885);
PAINT MONO (-3890 3885);
DISPLAY INVISIBLE (-3890 3885);
FORCEPROP 1 LAST HDL_POWER PVCCMCP_CPU0
J 1
(-3900 3975);
DISPLAY 0.617021 (-3900 3975);
PAINT GREEN (-3900 3975);
FORCEPROP 2 LAST ROOM PVMCP_FPGA_CPU0_VR
J 0
(-3900 4025);
DISPLAY 3.127660 (-3900 4025);
PAINT WHITE (-3900 4025);
DISPLAY INVISIBLE (-3900 4025);
FORCEPROP 1 LAST PATH I130
J 0
(-3850 3950);
DISPLAY 0.872340 (-3850 3950);
PAINT AQUA (-3850 3950);
DISPLAY INVISIBLE (-3850 3950);
FORCEPROP 2 LAST CDS_LIB mstr_symbols
J 0
(-3900 3925);
PAINT MONO (-3900 3925);
DISPLAY INVISIBLE (-3900 3925);
FORCEPROP 2 LAST BOM_COST PVMCP_FPGA_CPU0_VR
J 0
(-3900 4025);
DISPLAY 2.340426 (-3900 4025);
PAINT WHITE (-3900 4025);
DISPLAY INVISIBLE (-3900 4025);
FORCEADD OFFPAGE..4
(-5375 2025);
FORCEPROP 2 LAST $XR0 190 
J 0
(-5189 2025);
DISPLAY 0.638298 (-5189 2025);
PAINT MONO (-5189 2025);
FORCEPROP 2 LAST PATH I131
J 0
(-5175 2075);
DISPLAY 1.021277 (-5175 2075);
PAINT ORANGE (-5175 2075);
DISPLAY INVISIBLE (-5175 2075);
FORCEPROP 2 LAST CDS_LIB mstr_standard
J 0
(-5375 2025);
PAINT MONO (-5375 2025);
DISPLAY INVISIBLE (-5375 2025);
FORCEPROP 2 LAST ROOM P0V95_FPGA_CPU0_VR
J 0
(-5925 2100);
DISPLAY 1.361702 (-5925 2100);
PAINT ORANGE (-5925 2100);
DISPLAY INVISIBLE (-5925 2100);
FORCEPROP 1 LAST OFFPAGE TRUE
J 0
(-5050 1900);
DISPLAY 0.872340 (-5050 1900);
PAINT GREEN (-5050 1900);
DISPLAY INVISIBLE (-5050 1900);
FORCEPROP 1 LAST COMMENT_BODY TRUE
J 0
(-5400 1925);
DISPLAY 0.872340 (-5400 1925);
PAINT GREEN (-5400 1925);
DISPLAY INVISIBLE (-5400 1925);
FORCEADD OFFPAGE..2
(-5350 1975);
FORCEPROP 2 LAST $XR0 190 
J 0
(-5161 1975);
DISPLAY 0.638298 (-5161 1975);
PAINT MONO (-5161 1975);
FORCEPROP 2 LAST PATH I132
J 0
(-5150 2025);
DISPLAY 1.021277 (-5150 2025);
PAINT ORANGE (-5150 2025);
DISPLAY INVISIBLE (-5150 2025);
FORCEPROP 2 LAST CDS_LIB mstr_standard
J 0
(-5350 1975);
PAINT MONO (-5350 1975);
DISPLAY INVISIBLE (-5350 1975);
FORCEPROP 2 LAST ROOM P0V95_FPGA_CPU0_VR
J 0
(-5775 2050);
DISPLAY 1.361702 (-5775 2050);
PAINT ORANGE (-5775 2050);
DISPLAY INVISIBLE (-5775 2050);
FORCEPROP 1 LAST OFFPAGE TRUE
J 0
(-5025 1850);
DISPLAY 1.170213 (-5025 1850);
PAINT GREEN (-5025 1850);
DISPLAY INVISIBLE (-5025 1850);
FORCEPROP 1 LAST COMMENT_BODY TRUE
J 0
(-5395 1880);
DISPLAY 1.170213 (-5395 1880);
PAINT GREEN (-5395 1880);
DISPLAY INVISIBLE (-5395 1880);
FORCEADD OFFPAGE..2
(-5350 2325);
FORCEPROP 2 LAST $XR0 191 
J 0
(-5161 2325);
DISPLAY 0.638298 (-5161 2325);
PAINT MONO (-5161 2325);
FORCEPROP 2 LAST PATH I133
J 0
(-5150 2375);
DISPLAY 1.021277 (-5150 2375);
PAINT ORANGE (-5150 2375);
DISPLAY INVISIBLE (-5150 2375);
FORCEPROP 2 LAST ROOM P0V95_FPGA_CPU0_VR
J 0
(-5775 2400);
DISPLAY 1.361702 (-5775 2400);
PAINT ORANGE (-5775 2400);
DISPLAY INVISIBLE (-5775 2400);
FORCEPROP 2 LAST CDS_LIB mstr_standard
J 0
(-5350 2325);
PAINT MONO (-5350 2325);
DISPLAY INVISIBLE (-5350 2325);
FORCEPROP 1 LAST OFFPAGE TRUE
J 0
(-5025 2200);
DISPLAY 1.170213 (-5025 2200);
PAINT GREEN (-5025 2200);
DISPLAY INVISIBLE (-5025 2200);
FORCEPROP 1 LAST COMMENT_BODY TRUE
J 0
(-5395 2230);
DISPLAY 1.170213 (-5395 2230);
PAINT GREEN (-5395 2230);
DISPLAY INVISIBLE (-5395 2230);
FORCEADD OFFPAGE..4
(-5350 2375);
FORCEPROP 2 LAST $XR0 191 
J 0
(-5164 2375);
DISPLAY 0.638298 (-5164 2375);
PAINT MONO (-5164 2375);
FORCEPROP 2 LAST PATH I134
J 0
(-5150 2425);
DISPLAY 1.021277 (-5150 2425);
PAINT ORANGE (-5150 2425);
DISPLAY INVISIBLE (-5150 2425);
FORCEPROP 2 LAST ROOM P0V95_FPGA_CPU0_VR
J 0
(-5900 2450);
DISPLAY 1.361702 (-5900 2450);
PAINT ORANGE (-5900 2450);
DISPLAY INVISIBLE (-5900 2450);
FORCEPROP 2 LAST CDS_LIB mstr_standard
J 0
(-5350 2375);
PAINT MONO (-5350 2375);
DISPLAY INVISIBLE (-5350 2375);
FORCEPROP 1 LAST OFFPAGE TRUE
J 0
(-5025 2250);
DISPLAY 0.872340 (-5025 2250);
PAINT GREEN (-5025 2250);
DISPLAY INVISIBLE (-5025 2250);
FORCEPROP 1 LAST COMMENT_BODY TRUE
J 0
(-5375 2275);
DISPLAY 0.872340 (-5375 2275);
PAINT GREEN (-5375 2275);
DISPLAY INVISIBLE (-5375 2275);
FORCEADD VCC_CORE..1
(-4175 4050);
FORCEPROP 3 LASTPIN (-4175 4000) SIG_NAME P1V8_MCP_CPU0\g
J 0
(-4165 4010);
DISPLAY 0.659574 (-4165 4010);
PAINT MONO (-4165 4010);
DISPLAY INVISIBLE (-4165 4010);
FORCEPROP 1 LAST HDL_POWER P1V8_MCP_CPU0
J 1
(-4175 4100);
DISPLAY 0.617021 (-4175 4100);
PAINT GREEN (-4175 4100);
FORCEPROP 1 LAST PATH I141
J 0
(-4125 4075);
DISPLAY 0.872340 (-4125 4075);
PAINT AQUA (-4125 4075);
DISPLAY INVISIBLE (-4125 4075);
FORCEPROP 2 LAST CDS_LIB mstr_symbols
J 0
(-4175 4050);
PAINT ORANGE (-4175 4050);
DISPLAY INVISIBLE (-4175 4050);
FORCEADD VCC_CORE..1
(-1900 2075);
FORCEPROP 3 LASTPIN (-1900 2025) SIG_NAME P1V8_MCP_CPU0\g
J 0
(-1890 2035);
DISPLAY 0.659574 (-1890 2035);
PAINT MONO (-1890 2035);
DISPLAY INVISIBLE (-1890 2035);
FORCEPROP 1 LAST HDL_POWER P1V8_MCP_CPU0
J 1
(-1900 2125);
DISPLAY 0.617021 (-1900 2125);
PAINT GREEN (-1900 2125);
FORCEPROP 1 LAST PATH I142
J 0
(-1850 2100);
DISPLAY 0.872340 (-1850 2100);
PAINT AQUA (-1850 2100);
DISPLAY INVISIBLE (-1850 2100);
FORCEPROP 2 LAST CDS_LIB mstr_symbols
J 0
(-1900 2075);
PAINT ORANGE (-1900 2075);
DISPLAY INVISIBLE (-1900 2075);
FORCEADD VCC_CORE..1
(-1300 2075);
FORCEPROP 3 LASTPIN (-1300 2025) SIG_NAME P1V8_MCP_CPU0\g
J 0
(-1290 2035);
DISPLAY 0.659574 (-1290 2035);
PAINT MONO (-1290 2035);
DISPLAY INVISIBLE (-1290 2035);
FORCEPROP 1 LAST HDL_POWER P1V8_MCP_CPU0
J 1
(-1300 2125);
DISPLAY 0.617021 (-1300 2125);
PAINT GREEN (-1300 2125);
FORCEPROP 1 LAST PATH I143
J 0
(-1250 2100);
DISPLAY 0.872340 (-1250 2100);
PAINT AQUA (-1250 2100);
DISPLAY INVISIBLE (-1250 2100);
FORCEPROP 2 LAST CDS_LIB mstr_symbols
J 0
(-1300 2075);
PAINT ORANGE (-1300 2075);
DISPLAY INVISIBLE (-1300 2075);
FORCEADD VCC_CORE..1
(-5450 2575);
FORCEPROP 3 LASTPIN (-5450 2525) SIG_NAME PVCCIOMCP_CPU0\g
J 0
(-5440 2535);
DISPLAY 0.659574 (-5440 2535);
PAINT MONO (-5440 2535);
DISPLAY INVISIBLE (-5440 2535);
FORCEPROP 1 LAST HDL_POWER PVCCIOMCP_CPU0
J 1
(-5450 2625);
DISPLAY 0.617021 (-5450 2625);
PAINT GREEN (-5450 2625);
FORCEPROP 1 LAST PATH I144
J 0
(-5400 2600);
DISPLAY 0.872340 (-5400 2600);
PAINT AQUA (-5400 2600);
DISPLAY INVISIBLE (-5400 2600);
FORCEPROP 2 LAST CDS_LIB mstr_symbols
J 0
(-5450 2575);
PAINT ORANGE (-5450 2575);
DISPLAY INVISIBLE (-5450 2575);
FORCEPROP 0 LAST VOLTAGE +0.95
J 0
(-5450 2725);
DISPLAY 1.021277 (-5450 2725);
PAINT SKYBLUE (-5450 2725);
DISPLAY INVISIBLE (-5450 2725);
FORCEADD OFFPAGE..2
(-5250 975);
FORCEPROP 2 LAST $XR0 201 
J 0
(-5061 975);
DISPLAY 0.638298 (-5061 975);
PAINT MONO (-5061 975);
FORCEPROP 2 LAST $XR1 211 
J 0
(-4941 975);
DISPLAY 0.638298 (-4941 975);
PAINT MONO (-4941 975);
FORCEPROP 2 LAST $XR2 21 
J 0
(-4821 975);
DISPLAY 0.638298 (-4821 975);
PAINT MONO (-4821 975);
FORCEPROP 2 LAST PATH I148
J 0
(-4625 1025);
DISPLAY 1.021277 (-4625 1025);
PAINT ORANGE (-4625 1025);
DISPLAY INVISIBLE (-4625 1025);
FORCEPROP 2 LAST ROOM P0V95_FPGA_CPU0_VR
J 0
(-5675 1050);
DISPLAY 1.361702 (-5675 1050);
PAINT ORANGE (-5675 1050);
DISPLAY INVISIBLE (-5675 1050);
FORCEPROP 2 LAST CDS_LIB mstr_standard
J 0
(-5250 975);
PAINT ORANGE (-5250 975);
DISPLAY INVISIBLE (-5250 975);
FORCEPROP 1 LAST OFFPAGE TRUE
J 0
(-4925 850);
DISPLAY 1.170213 (-4925 850);
PAINT GREEN (-4925 850);
DISPLAY INVISIBLE (-4925 850);
FORCEPROP 1 LAST COMMENT_BODY TRUE
J 0
(-5295 880);
DISPLAY 1.170213 (-5295 880);
PAINT GREEN (-5295 880);
DISPLAY INVISIBLE (-5295 880);
FORCEADD CAP_A..1
(-1600 1850);
FORCEPROP 0 LAST GROUP PWR_MCP_CAP
J 0
(-1550 1525);
DISPLAY 0.638298 (-1550 1525);
PAINT BROWN (-1550 1525);
DISPLAY BOTH (-1550 1525);
FORCEPROP 1 LAST PACK_TYPE 0603V
J 0
(-1550 1650);
DISPLAY 0.617021 (-1550 1650);
PAINT SKYBLUE (-1550 1650);
FORCEPROP 1 LAST PART_NUMBER 602433-106
J 0
(-1550 1700);
DISPLAY 0.617021 (-1550 1700);
PAINT BLUE (-1550 1700);
FORCEPROP 1 LAST MATERIAL X5R
J 0
(-1550 1750);
DISPLAY 0.617021 (-1550 1750);
PAINT SKYBLUE (-1550 1750);
FORCEPROP 1 LAST TOLERANCE 20%
J 0
(-1550 1800);
DISPLAY 0.617021 (-1550 1800);
PAINT SKYBLUE (-1550 1800);
FORCEPROP 1 LAST VOLTAGE 4V
J 0
(-1550 1850);
DISPLAY 0.617021 (-1550 1850);
PAINT SKYBLUE (-1550 1850);
FORCEPROP 1 LAST VALUE 47UF
J 0
(-1550 1900);
DISPLAY 0.617021 (-1550 1900);
PAINT SKYBLUE (-1550 1900);
FORCEPROP 1 LASTPIN (-1600 1950) $PN 1
J 0
(-1590 1930);
DISPLAY 0.617021 (-1590 1930);
PAINT ORANGE (-1590 1930);
FORCEPROP 1 LAST LOCATION C3T1
J 0
(-1550 1950);
DISPLAY 0.617021 (-1550 1950);
PAINT AQUA (-1550 1950);
FORCEPROP 1 LASTPIN (-1600 1750) $PN 2
J 0
(-1590 1730);
DISPLAY 0.617021 (-1590 1730);
PAINT ORANGE (-1590 1730);
FORCEPROP 2 LAST CDS_LOCATION C3T1
J 0
(-1550 1950);
DISPLAY 0.617021 (-1550 1950);
PAINT AQUA (-1550 1950);
DISPLAY INVISIBLE (-1550 1950);
FORCEPROP 2 LAST CDS_LIB dev_discrete
J 0
(-1600 1850);
PAINT ORANGE (-1600 1850);
DISPLAY INVISIBLE (-1600 1850);
FORCEPROP 2 LAST CDS_SEC 1
J 0
(-1550 2000);
PAINT ORANGE (-1550 2000);
DISPLAY INVISIBLE (-1550 2000);
FORCEPROP 2 LAST SEC_TYPE 0603V
J 0
(-1550 2050);
DISPLAY 1.021277 (-1550 2050);
PAINT ORANGE (-1550 2050);
DISPLAY INVISIBLE (-1550 2050);
FORCEPROP 2 LAST SEC 1
J 0
(-1550 2050);
PAINT MONO (-1550 2050);
DISPLAY INVISIBLE (-1550 2050);
FORCEPROP 1 LAST PATH I149
J 0
(-1550 2000);
DISPLAY 0.978723 (-1550 2000);
PAINT WHITE (-1550 2000);
DISPLAY INVISIBLE (-1550 2000);
FORCEADD CAP_A..1
(-1900 1850);
FORCEPROP 0 LAST GROUP PWR_MCP_CAP
J 0
(-1850 1600);
DISPLAY 0.638298 (-1850 1600);
PAINT BROWN (-1850 1600);
DISPLAY BOTH (-1850 1600);
FORCEPROP 1 LAST LOCATION C3T2
J 0
(-1850 1950);
DISPLAY 0.617021 (-1850 1950);
PAINT AQUA (-1850 1950);
FORCEPROP 1 LAST VALUE 47UF
J 0
(-1850 1900);
DISPLAY 0.617021 (-1850 1900);
PAINT SKYBLUE (-1850 1900);
FORCEPROP 1 LAST PART_NUMBER 602433-106
J 0
(-1850 1700);
DISPLAY 0.617021 (-1850 1700);
PAINT BLUE (-1850 1700);
FORCEPROP 1 LAST PACK_TYPE 0603V
J 0
(-1850 1650);
DISPLAY 0.617021 (-1850 1650);
PAINT SKYBLUE (-1850 1650);
FORCEPROP 1 LAST VOLTAGE 4V
J 0
(-1850 1850);
DISPLAY 0.617021 (-1850 1850);
PAINT SKYBLUE (-1850 1850);
FORCEPROP 1 LASTPIN (-1900 1950) $PN 1
J 0
(-1890 1930);
DISPLAY 0.617021 (-1890 1930);
PAINT ORANGE (-1890 1930);
FORCEPROP 1 LASTPIN (-1900 1750) $PN 2
J 0
(-1890 1730);
DISPLAY 0.617021 (-1890 1730);
PAINT ORANGE (-1890 1730);
FORCEPROP 1 LAST TOLERANCE 20%
J 0
(-1850 1800);
DISPLAY 0.617021 (-1850 1800);
PAINT SKYBLUE (-1850 1800);
FORCEPROP 1 LAST MATERIAL X5R
J 0
(-1850 1750);
DISPLAY 0.617021 (-1850 1750);
PAINT SKYBLUE (-1850 1750);
FORCEPROP 2 LAST CDS_LOCATION C3T2
J 0
(-1850 1950);
DISPLAY 0.617021 (-1850 1950);
PAINT AQUA (-1850 1950);
DISPLAY INVISIBLE (-1850 1950);
FORCEPROP 2 LAST CDS_LIB dev_discrete
J 0
(-1900 1850);
PAINT ORANGE (-1900 1850);
DISPLAY INVISIBLE (-1900 1850);
FORCEPROP 2 LAST CDS_SEC 1
J 0
(-1850 2000);
PAINT ORANGE (-1850 2000);
DISPLAY INVISIBLE (-1850 2000);
FORCEPROP 2 LAST SEC_TYPE 0603V
J 0
(-1850 2050);
DISPLAY 1.021277 (-1850 2050);
PAINT ORANGE (-1850 2050);
DISPLAY INVISIBLE (-1850 2050);
FORCEPROP 2 LAST SEC 1
J 0
(-1850 2050);
PAINT MONO (-1850 2050);
DISPLAY INVISIBLE (-1850 2050);
FORCEPROP 1 LAST PATH I150
J 0
(-1850 2000);
DISPLAY 0.978723 (-1850 2000);
PAINT WHITE (-1850 2000);
DISPLAY INVISIBLE (-1850 2000);
FORCEADD GND..1
(-1300 1575);
FORCEPROP 3 LASTPIN (-1300 1625) SIG_NAME GND\g
J 0
(-1290 1635);
DISPLAY 0.659574 (-1290 1635);
PAINT MONO (-1290 1635);
DISPLAY INVISIBLE (-1290 1635);
FORCEPROP 1 LAST PATH I151
J 0
(-1225 1575);
DISPLAY 0.872340 (-1225 1575);
PAINT AQUA (-1225 1575);
DISPLAY INVISIBLE (-1225 1575);
FORCEPROP 2 LAST CDS_LIB mstr_symbols
J 0
(-1300 1575);
PAINT ORANGE (-1300 1575);
DISPLAY INVISIBLE (-1300 1575);
FORCEPROP 1 LAST SIZE 1B
J 0
(-1225 1525);
DISPLAY 1.191489 (-1225 1525);
PAINT GREEN (-1225 1525);
DISPLAY INVISIBLE (-1225 1525);
FORCEPROP 1 LAST VOLTAGE 0
J 0
(-1300 1575);
DISPLAY 1.340426 (-1300 1575);
PAINT SKYBLUE (-1300 1575);
DISPLAY INVISIBLE (-1300 1575);
FORCEPROP 1 LAST BODY_TYPE PLUMBING
J 0
(-1345 1532);
DISPLAY 0.340426 (-1345 1532);
PAINT GREEN (-1345 1532);
DISPLAY INVISIBLE (-1345 1532);
FORCEPROP 1 LAST HDL_POWER GND
J 0
(-1300 1725);
DISPLAY 1.191489 (-1300 1725);
PAINT GREEN (-1300 1725);
DISPLAY INVISIBLE (-1300 1725);
FORCEADD PVCCIO_CPU0..1
(-7425 3900);
FORCEPROP 3 LASTPIN (-7425 3850) SIG_NAME PVCCIO_CPU0\g
J 0
(-7415 3860);
DISPLAY 0.659574 (-7415 3860);
PAINT MONO (-7415 3860);
DISPLAY INVISIBLE (-7415 3860);
FORCEPROP 1 LAST PATH I154
J 0
(-7375 3925);
DISPLAY 0.872340 (-7375 3925);
PAINT AQUA (-7375 3925);
DISPLAY INVISIBLE (-7375 3925);
FORCEPROP 2 LAST CDS_LIB mstr_symbols
J 0
(-7425 3900);
PAINT ORANGE (-7425 3900);
DISPLAY INVISIBLE (-7425 3900);
FORCEPROP 1 LAST VOLTAGE 1.1V
J 0
(-7470 3857);
DISPLAY 0.340426 (-7470 3857);
PAINT SKYBLUE (-7470 3857);
DISPLAY INVISIBLE (-7470 3857);
FORCEPROP 1 LAST BODY_TYPE PLUMBING
J 0
(-7470 3857);
DISPLAY 0.340426 (-7470 3857);
PAINT GREEN (-7470 3857);
DISPLAY INVISIBLE (-7470 3857);
FORCEPROP 1 LAST HDL_POWER PVCCIO_CPU0
J 1
(-7425 3950);
DISPLAY 0.872340 (-7425 3950);
PAINT GREEN (-7425 3950);
DISPLAY INVISIBLE (-7425 3950);
FORCEADD RES..2
(-7825 100);
FORCEPROP 1 LAST PACK_TYPE 0402
J 0
(-7785 -75);
DISPLAY 0.617021 (-7785 -75);
PAINT SKYBLUE (-7785 -75);
FORCEPROP 1 LASTPIN (-7825 200) $PN 1
J 0
(-7820 162);
DISPLAY 0.617021 (-7820 162);
PAINT ORANGE (-7820 162);
FORCEPROP 1 LASTPIN (-7825 0) $PN 2
J 0
(-7820 10);
DISPLAY 0.617021 (-7820 10);
PAINT ORANGE (-7820 10);
FORCEPROP 1 LAST WATTAGE 1/16W
J 0
(-7785 75);
DISPLAY 0.617021 (-7785 75);
PAINT SKYBLUE (-7785 75);
FORCEPROP 1 LAST MATERIAL CHIP
J 0
(-7785 25);
DISPLAY 0.617021 (-7785 25);
PAINT SKYBLUE (-7785 25);
FORCEPROP 1 LAST TOLERANCE 1%
J 0
(-7780 125);
DISPLAY 0.617021 (-7780 125);
PAINT SKYBLUE (-7780 125);
FORCEPROP 1 LAST PART_NUMBER G21796-082
J 0
(-7785 -25);
DISPLAY 0.617021 (-7785 -25);
PAINT BLUE (-7785 -25);
FORCEPROP 0 LAST GROUP MCP
J 0
(-7800 -125);
DISPLAY 0.638298 (-7800 -125);
PAINT BROWN (-7800 -125);
DISPLAY BOTH (-7800 -125);
FORCEPROP 1 LAST LOCATION R7C24
J 0
(-7780 225);
DISPLAY 0.617021 (-7780 225);
PAINT AQUA (-7780 225);
FORCEPROP 1 LAST VALUE 4.02K
J 0
(-7780 175);
DISPLAY 0.617021 (-7780 175);
PAINT SKYBLUE (-7780 175);
FORCEPROP 0 LAST ROOM PVCCIN_CPU1_VR
J 0
(-7775 325);
DISPLAY 1.021277 (-7775 325);
PAINT ORANGE (-7775 325);
DISPLAY INVISIBLE (-7775 325);
FORCEPROP 1 LAST PATH I155
J 0
(-7775 275);
DISPLAY 0.978723 (-7775 275);
PAINT WHITE (-7775 275);
DISPLAY INVISIBLE (-7775 275);
FORCEPROP 2 LAST SEC 1
J 0
(-7775 325);
PAINT MONO (-7775 325);
DISPLAY INVISIBLE (-7775 325);
FORCEPROP 2 LAST CDS_LIB mstr_discrete
J 0
(-7825 100);
PAINT ORANGE (-7825 100);
DISPLAY INVISIBLE (-7825 100);
FORCEPROP 2 LAST SEC_TYPE 0402
J 0
(-7775 325);
DISPLAY 1.021277 (-7775 325);
PAINT ORANGE (-7775 325);
DISPLAY INVISIBLE (-7775 325);
FORCEADD RES..2
(-8175 125);
FORCEPROP 0 LAST GROUP MCP
J 0
(-8150 -100);
DISPLAY 0.638298 (-8150 -100);
PAINT BROWN (-8150 -100);
DISPLAY BOTH (-8150 -100);
FORCEPROP 1 LAST PACK_TYPE 0402
J 0
(-8135 -50);
DISPLAY 0.617021 (-8135 -50);
PAINT SKYBLUE (-8135 -50);
FORCEPROP 1 LAST WATTAGE 1/16W
J 0
(-8135 100);
DISPLAY 0.617021 (-8135 100);
PAINT SKYBLUE (-8135 100);
FORCEPROP 1 LASTPIN (-8175 225) $PN 1
J 0
(-8170 187);
DISPLAY 0.617021 (-8170 187);
PAINT ORANGE (-8170 187);
FORCEPROP 1 LASTPIN (-8175 25) $PN 2
J 0
(-8170 35);
DISPLAY 0.617021 (-8170 35);
PAINT ORANGE (-8170 35);
FORCEPROP 1 LAST TOLERANCE 1.0%
J 0
(-8130 150);
DISPLAY 0.617021 (-8130 150);
PAINT SKYBLUE (-8130 150);
FORCEPROP 1 LAST VALUE 16K
J 0
(-8130 200);
DISPLAY 0.617021 (-8130 200);
PAINT SKYBLUE (-8130 200);
FORCEPROP 1 LAST PART_NUMBER G21796-317
J 0
(-8135 0);
DISPLAY 0.617021 (-8135 0);
PAINT BLUE (-8135 0);
FORCEPROP 1 LAST LOCATION R3N29
J 0
(-8130 250);
DISPLAY 0.617021 (-8130 250);
PAINT AQUA (-8130 250);
FORCEPROP 1 LAST MATERIAL CHIP
J 0
(-8135 50);
DISPLAY 0.617021 (-8135 50);
PAINT SKYBLUE (-8135 50);
FORCEPROP 0 LAST ROOM VDDQ_ABC_PWR_VR
J 0
(-8125 350);
DISPLAY 1.021277 (-8125 350);
PAINT ORANGE (-8125 350);
DISPLAY INVISIBLE (-8125 350);
FORCEPROP 1 LAST PATH I156
J 0
(-8125 300);
DISPLAY 0.978723 (-8125 300);
PAINT WHITE (-8125 300);
DISPLAY INVISIBLE (-8125 300);
FORCEPROP 2 LAST SEC 1
J 0
(-8125 350);
PAINT MONO (-8125 350);
DISPLAY INVISIBLE (-8125 350);
FORCEPROP 2 LAST CDS_LIB mstr_discrete
J 0
(-8175 125);
PAINT ORANGE (-8175 125);
DISPLAY INVISIBLE (-8175 125);
FORCEPROP 2 LAST SEC_TYPE 0402
J 0
(-8125 350);
DISPLAY 1.021277 (-8125 350);
PAINT ORANGE (-8125 350);
DISPLAY INVISIBLE (-8125 350);
FORCEADD GND..1
(-7975 -225);
FORCEPROP 3 LASTPIN (-7975 -175) SIG_NAME GND\g
J 0
(-7965 -165);
DISPLAY 0.659574 (-7965 -165);
PAINT MONO (-7965 -165);
DISPLAY INVISIBLE (-7965 -165);
FORCEPROP 1 LAST PATH I157
J 0
(-7900 -225);
DISPLAY 0.872340 (-7900 -225);
PAINT AQUA (-7900 -225);
DISPLAY INVISIBLE (-7900 -225);
FORCEPROP 1 LAST SIZE 1B
J 0
(-7900 -275);
DISPLAY 1.404255 (-7900 -275);
PAINT AQUA (-7900 -275);
DISPLAY INVISIBLE (-7900 -275);
FORCEPROP 2 LAST CDS_LIB mstr_symbols
J 0
(-7975 -225);
PAINT ORANGE (-7975 -225);
DISPLAY INVISIBLE (-7975 -225);
FORCEPROP 1 LAST VOLTAGE 0.0V
J 0
(-8020 -268);
DISPLAY 0.340426 (-8020 -268);
PAINT SKYBLUE (-8020 -268);
DISPLAY INVISIBLE (-8020 -268);
FORCEPROP 1 LAST BODY_TYPE PLUMBING
J 0
(-8020 -268);
DISPLAY 0.340426 (-8020 -268);
PAINT GREEN (-8020 -268);
DISPLAY INVISIBLE (-8020 -268);
FORCEPROP 1 LAST HDL_POWER GND
J 0
(-7975 -75);
PAINT GREEN (-7975 -75);
DISPLAY INVISIBLE (-7975 -75);
FORCEADD OFFPAGE..2
(-5300 475);
FORCEPROP 2 LAST $XR0 190 
J 0
(-5111 475);
DISPLAY 0.638298 (-5111 475);
PAINT MONO (-5111 475);
FORCEPROP 2 LAST PATH I158
J 0
(-5100 525);
DISPLAY 1.021277 (-5100 525);
PAINT ORANGE (-5100 525);
DISPLAY INVISIBLE (-5100 525);
FORCEPROP 2 LAST ROOM P0V95_FPGA_CPU0_VR
J 0
(-5725 550);
DISPLAY 1.361702 (-5725 550);
PAINT ORANGE (-5725 550);
DISPLAY INVISIBLE (-5725 550);
FORCEPROP 2 LAST CDS_LIB mstr_standard
J 0
(-5300 475);
PAINT ORANGE (-5300 475);
DISPLAY INVISIBLE (-5300 475);
FORCEPROP 1 LAST OFFPAGE TRUE
J 0
(-4975 350);
DISPLAY 1.170213 (-4975 350);
PAINT GREEN (-4975 350);
DISPLAY INVISIBLE (-4975 350);
FORCEPROP 1 LAST COMMENT_BODY TRUE
J 0
(-5345 380);
DISPLAY 1.170213 (-5345 380);
PAINT GREEN (-5345 380);
DISPLAY INVISIBLE (-5345 380);
FORCEADD OFFPAGE..4
(-5300 525);
FORCEPROP 2 LAST $XR0 190 
J 0
(-5084 525);
DISPLAY 0.638298 (-5084 525);
PAINT MONO (-5084 525);
FORCEPROP 2 LAST PATH I159
J 0
(-5100 575);
DISPLAY 1.021277 (-5100 575);
PAINT ORANGE (-5100 575);
DISPLAY INVISIBLE (-5100 575);
FORCEPROP 2 LAST ROOM P0V95_FPGA_CPU0_VR
J 0
(-5850 600);
DISPLAY 1.361702 (-5850 600);
PAINT ORANGE (-5850 600);
DISPLAY INVISIBLE (-5850 600);
FORCEPROP 2 LAST CDS_LIB mstr_standard
J 0
(-5300 525);
PAINT ORANGE (-5300 525);
DISPLAY INVISIBLE (-5300 525);
FORCEPROP 1 LAST OFFPAGE TRUE
J 0
(-4975 400);
DISPLAY 0.872340 (-4975 400);
PAINT GREEN (-4975 400);
DISPLAY INVISIBLE (-4975 400);
FORCEPROP 1 LAST COMMENT_BODY TRUE
J 0
(-5325 425);
DISPLAY 0.872340 (-5325 425);
PAINT GREEN (-5325 425);
DISPLAY INVISIBLE (-5325 425);
FORCEADD CAP_A..1
(-1300 1850);
FORCEPROP 1 LASTPIN (-1300 1950) $PN 1
J 0
(-1290 1930);
DISPLAY 0.617021 (-1290 1930);
PAINT ORANGE (-1290 1930);
FORCEPROP 1 LAST LOCATION C4T1
J 0
(-1250 1950);
DISPLAY 0.617021 (-1250 1950);
PAINT AQUA (-1250 1950);
FORCEPROP 1 LAST VALUE 1.0UF
J 0
(-1250 1900);
DISPLAY 0.617021 (-1250 1900);
PAINT SKYBLUE (-1250 1900);
FORCEPROP 1 LAST VOLTAGE 6.3V
J 0
(-1250 1850);
DISPLAY 0.617021 (-1250 1850);
PAINT SKYBLUE (-1250 1850);
FORCEPROP 0 LAST GROUP PWR_MCP_CAP
J 0
(-1250 1600);
DISPLAY 0.638298 (-1250 1600);
PAINT BROWN (-1250 1600);
DISPLAY BOTH (-1250 1600);
FORCEPROP 1 LASTPIN (-1300 1750) $PN 2
J 0
(-1290 1730);
DISPLAY 0.617021 (-1290 1730);
PAINT ORANGE (-1290 1730);
FORCEPROP 1 LAST MATERIAL X6S
J 0
(-1250 1750);
DISPLAY 0.617021 (-1250 1750);
PAINT SKYBLUE (-1250 1750);
FORCEPROP 1 LAST PACK_TYPE 0402V
J 0
(-1250 1650);
DISPLAY 0.617021 (-1250 1650);
PAINT SKYBLUE (-1250 1650);
FORCEPROP 1 LAST TOLERANCE 10%
J 0
(-1250 1800);
DISPLAY 0.617021 (-1250 1800);
PAINT SKYBLUE (-1250 1800);
FORCEPROP 1 LAST PART_NUMBER D97712-004
J 0
(-1250 1700);
DISPLAY 0.617021 (-1250 1700);
PAINT BLUE (-1250 1700);
FORCEPROP 2 LAST ROOM P1V8_MCP_CPU0
J 0
(-1250 2000);
DISPLAY 1.659574 (-1250 2000);
PAINT WHITE (-1250 2000);
DISPLAY INVISIBLE (-1250 2000);
FORCEPROP 1 LAST PATH I16
J 0
(-1250 2000);
DISPLAY 0.978723 (-1250 2000);
PAINT WHITE (-1250 2000);
DISPLAY INVISIBLE (-1250 2000);
FORCEPROP 2 LAST SEC 1
J 2
(-1250 2050);
DISPLAY 0.680851 (-1250 2050);
PAINT MONO (-1250 2050);
DISPLAY INVISIBLE (-1250 2050);
FORCEPROP 2 LAST SEC_TYPE 0402V
J 2
(-1250 2050);
DISPLAY 1.021277 (-1250 2050);
PAINT ORANGE (-1250 2050);
DISPLAY INVISIBLE (-1250 2050);
FORCEPROP 2 LAST CDS_SEC 1
J 2
(-1250 2000);
PAINT ORANGE (-1250 2000);
DISPLAY INVISIBLE (-1250 2000);
FORCEPROP 2 LAST CDS_LIB dev_discrete
J 2
(-1300 1850);
PAINT ORANGE (-1300 1850);
DISPLAY INVISIBLE (-1300 1850);
FORCEPROP 2 LAST CDS_LOCATION C4T1
J 0
(-1250 1950);
DISPLAY 0.617021 (-1250 1950);
PAINT AQUA (-1250 1950);
DISPLAY INVISIBLE (-1250 1950);
FORCEADD OFFPAGE..3
(-5325 375);
FORCEPROP 2 LAST $XR2 218 
J 0
(-4901 375);
DISPLAY 0.638298 (-4901 375);
PAINT MONO (-4901 375);
FORCEPROP 2 LAST $XR0 21 
J 0
(-5111 375);
DISPLAY 0.638298 (-5111 375);
PAINT MONO (-5111 375);
FORCEPROP 2 LAST $XR1 215 
J 0
(-5021 375);
DISPLAY 0.638298 (-5021 375);
PAINT MONO (-5021 375);
FORCEPROP 2 LAST PATH I160
J 0
(-4900 425);
DISPLAY 1.021277 (-4900 425);
PAINT ORANGE (-4900 425);
DISPLAY INVISIBLE (-4900 425);
FORCEPROP 2 LAST CDS_LIB mstr_standard
J 0
(-5325 375);
PAINT ORANGE (-5325 375);
DISPLAY INVISIBLE (-5325 375);
FORCEPROP 2 LAST ROOM P0V95_FPGA_CPU0_VR
J 0
(-5725 450);
DISPLAY 1.361702 (-5725 450);
PAINT ORANGE (-5725 450);
DISPLAY INVISIBLE (-5725 450);
FORCEPROP 1 LAST OFFPAGE TRUE
J 0
(-5000 250);
DISPLAY 1.170213 (-5000 250);
PAINT GREEN (-5000 250);
DISPLAY INVISIBLE (-5000 250);
FORCEPROP 1 LAST COMMENT_BODY TRUE
J 0
(-5375 275);
DISPLAY 1.170213 (-5375 275);
PAINT GREEN (-5375 275);
DISPLAY INVISIBLE (-5375 275);
FORCEADD OFFPAGE..4
(-5325 425);
FORCEPROP 2 LAST $XR2 218 
J 0
(-4899 425);
DISPLAY 0.638298 (-4899 425);
PAINT MONO (-4899 425);
FORCEPROP 2 LAST $XR1 215 
J 0
(-5019 425);
DISPLAY 0.638298 (-5019 425);
PAINT MONO (-5019 425);
FORCEPROP 2 LAST $XR0 21 
J 0
(-5109 425);
DISPLAY 0.638298 (-5109 425);
PAINT MONO (-5109 425);
FORCEPROP 2 LAST PATH I161
J 0
(-4875 475);
DISPLAY 1.021277 (-4875 475);
PAINT ORANGE (-4875 475);
DISPLAY INVISIBLE (-4875 475);
FORCEPROP 2 LAST CDS_LIB mstr_standard
J 0
(-5325 425);
PAINT MONO (-5325 425);
DISPLAY INVISIBLE (-5325 425);
FORCEPROP 2 LAST ROOM P0V95_FPGA_CPU0_VR
J 0
(-5875 500);
DISPLAY 1.361702 (-5875 500);
PAINT ORANGE (-5875 500);
DISPLAY INVISIBLE (-5875 500);
FORCEPROP 1 LAST OFFPAGE TRUE
J 0
(-5000 300);
DISPLAY 0.872340 (-5000 300);
PAINT GREEN (-5000 300);
DISPLAY INVISIBLE (-5000 300);
FORCEPROP 1 LAST COMMENT_BODY TRUE
J 0
(-5350 325);
DISPLAY 0.872340 (-5350 325);
PAINT GREEN (-5350 325);
DISPLAY INVISIBLE (-5350 325);
FORCEADD OFFPAGE..3
(-5275 575);
FORCEPROP 2 LAST $XR2 211 
J 0
(-4851 575);
DISPLAY 0.638298 (-4851 575);
PAINT MONO (-4851 575);
FORCEPROP 2 LAST $XR0 21 
J 0
(-5061 575);
DISPLAY 0.638298 (-5061 575);
PAINT MONO (-5061 575);
FORCEPROP 2 LAST $XR1 201 
J 0
(-4971 575);
DISPLAY 0.638298 (-4971 575);
PAINT MONO (-4971 575);
FORCEPROP 2 LAST PATH I162
J 0
(-4850 625);
DISPLAY 1.021277 (-4850 625);
PAINT ORANGE (-4850 625);
DISPLAY INVISIBLE (-4850 625);
FORCEPROP 2 LAST CDS_LIB mstr_standard
J 0
(-5275 575);
PAINT ORANGE (-5275 575);
DISPLAY INVISIBLE (-5275 575);
FORCEPROP 2 LAST ROOM P0V95_FPGA_CPU0_VR
J 0
(-5675 650);
DISPLAY 1.361702 (-5675 650);
PAINT ORANGE (-5675 650);
DISPLAY INVISIBLE (-5675 650);
FORCEPROP 1 LAST OFFPAGE TRUE
J 0
(-4950 450);
DISPLAY 1.170213 (-4950 450);
PAINT GREEN (-4950 450);
DISPLAY INVISIBLE (-4950 450);
FORCEPROP 1 LAST COMMENT_BODY TRUE
J 0
(-5325 475);
DISPLAY 1.170213 (-5325 475);
PAINT GREEN (-5325 475);
DISPLAY INVISIBLE (-5325 475);
FORCEADD OFFPAGE..2
(-5250 925);
FORCEPROP 2 LAST $XR0 215 
J 0
(-5061 925);
DISPLAY 0.638298 (-5061 925);
PAINT MONO (-5061 925);
FORCEPROP 2 LAST $XR2 21 
J 0
(-4821 925);
DISPLAY 0.638298 (-4821 925);
PAINT MONO (-4821 925);
FORCEPROP 2 LAST $XR1 218 
J 0
(-4941 925);
DISPLAY 0.638298 (-4941 925);
PAINT MONO (-4941 925);
FORCEPROP 2 LAST PATH I163
J 0
(-4800 975);
DISPLAY 1.021277 (-4800 975);
PAINT ORANGE (-4800 975);
DISPLAY INVISIBLE (-4800 975);
FORCEPROP 2 LAST CDS_LIB mstr_standard
J 0
(-5250 925);
PAINT ORANGE (-5250 925);
DISPLAY INVISIBLE (-5250 925);
FORCEPROP 2 LAST ROOM P0V95_FPGA_CPU0_VR
J 0
(-5675 1000);
DISPLAY 1.361702 (-5675 1000);
PAINT ORANGE (-5675 1000);
DISPLAY INVISIBLE (-5675 1000);
FORCEPROP 1 LAST OFFPAGE TRUE
J 0
(-4925 800);
DISPLAY 1.170213 (-4925 800);
PAINT GREEN (-4925 800);
DISPLAY INVISIBLE (-4925 800);
FORCEPROP 1 LAST COMMENT_BODY TRUE
J 0
(-5295 830);
DISPLAY 1.170213 (-5295 830);
PAINT GREEN (-5295 830);
DISPLAY INVISIBLE (-5295 830);
FORCEADD OFFPAGE..1
(-5000 3475);
FORCEPROP 2 LAST $XR0 22 
J 0
(-5221 3475);
DISPLAY 0.638298 (-5221 3475);
PAINT MONO (-5221 3475);
FORCEPROP 2 LAST PATH I164
J 0
(-4950 3550);
DISPLAY 1.021277 (-4950 3550);
PAINT ORANGE (-4950 3550);
DISPLAY INVISIBLE (-4950 3550);
FORCEPROP 2 LAST CDS_LIB mstr_standard
J 0
(-5000 3475);
PAINT ORANGE (-5000 3475);
DISPLAY INVISIBLE (-5000 3475);
FORCEPROP 1 LAST OFFPAGE TRUE
J 0
(-4675 3350);
DISPLAY 1.170213 (-4675 3350);
PAINT GREEN (-4675 3350);
DISPLAY INVISIBLE (-4675 3350);
FORCEPROP 1 LAST COMMENT_BODY TRUE
J 0
(-4875 3375);
DISPLAY 1.170213 (-4875 3375);
PAINT GREEN (-4875 3375);
DISPLAY INVISIBLE (-4875 3375);
FORCEADD OFFPAGE..1
(-5000 3550);
FORCEPROP 2 LAST $XR0 22 
J 0
(-5221 3550);
DISPLAY 0.638298 (-5221 3550);
PAINT MONO (-5221 3550);
FORCEPROP 2 LAST PATH I165
J 0
(-4950 3625);
DISPLAY 1.021277 (-4950 3625);
PAINT ORANGE (-4950 3625);
DISPLAY INVISIBLE (-4950 3625);
FORCEPROP 2 LAST CDS_LIB mstr_standard
J 0
(-5000 3550);
PAINT ORANGE (-5000 3550);
DISPLAY INVISIBLE (-5000 3550);
FORCEPROP 1 LAST OFFPAGE TRUE
J 0
(-4675 3425);
DISPLAY 1.170213 (-4675 3425);
PAINT GREEN (-4675 3425);
DISPLAY INVISIBLE (-4675 3425);
FORCEPROP 1 LAST COMMENT_BODY TRUE
J 0
(-4875 3450);
DISPLAY 1.170213 (-4875 3450);
PAINT GREEN (-4875 3450);
DISPLAY INVISIBLE (-4875 3450);
FORCEADD OFFPAGE..5
(-4850 2200);
FORCEPROP 2 LAST PATH I166
J 0
(-5100 2250);
DISPLAY 1.021277 (-5100 2250);
PAINT ORANGE (-5100 2250);
DISPLAY INVISIBLE (-5100 2250);
FORCEPROP 2 LAST BOM_COST PROC_VRD_VCCIN_CPU0
J 0
(-4525 2250);
PAINT MONO (-4525 2250);
DISPLAY INVISIBLE (-4525 2250);
FORCEPROP 2 LAST ROOM PVSA_CPU0_VSENSE_VR
J 0
(-5250 2275);
PAINT ORANGE (-5250 2275);
DISPLAY INVISIBLE (-5250 2275);
FORCEPROP 2 LAST CDS_LIB mstr_standard
J 0
(-4850 2200);
PAINT ORANGE (-4850 2200);
DISPLAY INVISIBLE (-4850 2200);
FORCEPROP 2 LAST $XR0 104 
J 0
(-5279 2200);
DISPLAY 0.638298 (-5279 2200);
PAINT MONO (-5279 2200);
DISPLAY INVISIBLE (-5279 2200);
FORCEPROP 1 LAST OFFPAGE TRUE
J 0
(-4525 2075);
DISPLAY 0.872340 (-4525 2075);
PAINT GREEN (-4525 2075);
DISPLAY INVISIBLE (-4525 2075);
FORCEPROP 1 LAST COMMENT_BODY TRUE
J 0
(-4750 2125);
DISPLAY 0.872340 (-4750 2125);
PAINT GREEN (-4750 2125);
DISPLAY INVISIBLE (-4750 2125);
FORCEADD OFFPAGE..5
(-4875 2150);
FORCEPROP 2 LAST $XR0 104 
J 0
(-5130 2150);
DISPLAY 0.638298 (-5130 2150);
PAINT MONO (-5130 2150);
FORCEPROP 2 LAST PATH I167
J 0
(-5125 2200);
DISPLAY 1.021277 (-5125 2200);
PAINT ORANGE (-5125 2200);
DISPLAY INVISIBLE (-5125 2200);
FORCEPROP 2 LAST BOM_COST PROC_VRD_VCCIN_CPU0
J 0
(-4550 2200);
PAINT MONO (-4550 2200);
DISPLAY INVISIBLE (-4550 2200);
FORCEPROP 2 LAST ROOM PVSA_CPU0_VSENSE_VR
J 0
(-5275 2225);
PAINT ORANGE (-5275 2225);
DISPLAY INVISIBLE (-5275 2225);
FORCEPROP 2 LAST CDS_LIB mstr_standard
J 0
(-4875 2150);
PAINT ORANGE (-4875 2150);
DISPLAY INVISIBLE (-4875 2150);
FORCEPROP 1 LAST OFFPAGE TRUE
J 0
(-4550 2025);
DISPLAY 0.872340 (-4550 2025);
PAINT GREEN (-4550 2025);
DISPLAY INVISIBLE (-4550 2025);
FORCEPROP 1 LAST COMMENT_BODY TRUE
J 0
(-4775 2075);
DISPLAY 0.872340 (-4775 2075);
PAINT GREEN (-4775 2075);
DISPLAY INVISIBLE (-4775 2075);
FORCEADD P3V3..1
(-7525 3800);
FORCEPROP 3 LASTPIN (-7525 3750) SIG_NAME P3V3\g
J 0
(-7515 3760);
DISPLAY 0.659574 (-7515 3760);
PAINT MONO (-7515 3760);
DISPLAY INVISIBLE (-7515 3760);
FORCEPROP 1 LAST PATH I170
J 0
(-7480 3802);
DISPLAY 0.340426 (-7480 3802);
PAINT GREEN (-7480 3802);
DISPLAY INVISIBLE (-7480 3802);
FORCEPROP 1 LAST SIZE 1B
J 0
(-7480 3822);
DISPLAY 0.340426 (-7480 3822);
PAINT GREEN (-7480 3822);
DISPLAY INVISIBLE (-7480 3822);
FORCEPROP 2 LAST CDS_LIB mstr_symbols
J 0
(-7525 3800);
PAINT ORANGE (-7525 3800);
DISPLAY INVISIBLE (-7525 3800);
FORCEPROP 1 LAST VOLTAGE +3.3V
J 0
(-7425 3950);
DISPLAY 1.021277 (-7425 3950);
PAINT SKYBLUE (-7425 3950);
DISPLAY INVISIBLE (-7425 3950);
FORCEPROP 1 LAST BODY_TYPE PLUMBING
J 0
(-7570 3757);
DISPLAY 0.340426 (-7570 3757);
PAINT GREEN (-7570 3757);
DISPLAY INVISIBLE (-7570 3757);
FORCEPROP 1 LAST HDL_POWER P3V3
J 0
(-7850 3675);
DISPLAY 0.872340 (-7850 3675);
PAINT ORANGE (-7850 3675);
DISPLAY INVISIBLE (-7850 3675);
FORCEADD OFFPAGE..1
(-8125 3575);
FORCEPROP 2 LAST $XR0 104 
J 0
(-8377 3575);
DISPLAY 0.638298 (-8377 3575);
PAINT MONO (-8377 3575);
FORCEPROP 2 LAST PATH I171
J 0
(-8075 3650);
DISPLAY 1.021277 (-8075 3650);
PAINT ORANGE (-8075 3650);
DISPLAY INVISIBLE (-8075 3650);
FORCEPROP 2 LAST CDS_LIB mstr_standard
J 0
(-8125 3575);
PAINT ORANGE (-8125 3575);
DISPLAY INVISIBLE (-8125 3575);
FORCEPROP 1 LAST OFFPAGE TRUE
J 0
(-7800 3450);
DISPLAY 1.170213 (-7800 3450);
PAINT GREEN (-7800 3450);
DISPLAY INVISIBLE (-7800 3450);
FORCEPROP 1 LAST COMMENT_BODY TRUE
J 0
(-8000 3475);
DISPLAY 1.170213 (-8000 3475);
PAINT GREEN (-8000 3475);
DISPLAY INVISIBLE (-8000 3475);
FORCEADD GND..1
(-1900 1575);
FORCEPROP 3 LASTPIN (-1900 1625) SIG_NAME GND\g
J 0
(-1890 1635);
DISPLAY 0.659574 (-1890 1635);
PAINT MONO (-1890 1635);
DISPLAY INVISIBLE (-1890 1635);
FORCEPROP 1 LAST VOLTAGE 0
J 0
(-1900 1575);
DISPLAY 1.340426 (-1900 1575);
PAINT SKYBLUE (-1900 1575);
DISPLAY INVISIBLE (-1900 1575);
FORCEPROP 1 LAST SIZE 1B
J 0
(-1825 1525);
DISPLAY 1.191489 (-1825 1525);
PAINT GREEN (-1825 1525);
DISPLAY INVISIBLE (-1825 1525);
FORCEPROP 2 LAST CDS_LIB mstr_symbols
J 0
(-1900 1575);
PAINT ORANGE (-1900 1575);
DISPLAY INVISIBLE (-1900 1575);
FORCEPROP 1 LAST PATH I28
J 0
(-1825 1575);
DISPLAY 0.872340 (-1825 1575);
PAINT AQUA (-1825 1575);
DISPLAY INVISIBLE (-1825 1575);
FORCEPROP 1 LAST BODY_TYPE PLUMBING
J 0
(-1945 1532);
DISPLAY 0.340426 (-1945 1532);
PAINT GREEN (-1945 1532);
DISPLAY INVISIBLE (-1945 1532);
FORCEPROP 1 LAST HDL_POWER GND
J 0
(-1900 1725);
DISPLAY 1.191489 (-1900 1725);
PAINT GREEN (-1900 1725);
DISPLAY INVISIBLE (-1900 1725);
FORCEADD CAPP..1
(-1600 2500);
FORCEPROP 1 LAST LOCATION C4R1
J 0
(-1550 2600);
DISPLAY 0.617021 (-1550 2600);
PAINT AQUA (-1550 2600);
FORCEPROP 1 LAST VALUE 470UF
J 0
(-1550 2550);
DISPLAY 0.617021 (-1550 2550);
PAINT SKYBLUE (-1550 2550);
FORCEPROP 0 LAST GROUP PWR_MCP_CAP
J 0
(-1550 2200);
DISPLAY 0.638298 (-1550 2200);
PAINT BROWN (-1550 2200);
DISPLAY BOTH (-1550 2200);
FORCEPROP 1 LAST PACK_TYPE 3018
J 0
(-1550 2350);
DISPLAY 0.617021 (-1550 2350);
PAINT SKYBLUE (-1550 2350);
FORCEPROP 1 LAST TOLERANCE 20%
J 0
(-1550 2500);
DISPLAY 0.617021 (-1550 2500);
PAINT SKYBLUE (-1550 2500);
FORCEPROP 1 LAST VOLTAGE 2.5V
J 0
(-1550 2450);
DISPLAY 0.659574 (-1550 2450);
PAINT SKYBLUE (-1550 2450);
FORCEPROP 1 LASTPIN (-1600 2400) $PN 2
J 0
(-1590 2385);
DISPLAY 0.617021 (-1590 2385);
PAINT WHITE (-1590 2385);
FORCEPROP 1 LAST MATERIAL ALUM
J 0
(-1550 2400);
DISPLAY 0.617021 (-1550 2400);
PAINT SKYBLUE (-1550 2400);
FORCEPROP 1 LAST PART_NUMBER 699013-049
J 0
(-1550 2300);
DISPLAY 0.617021 (-1550 2300);
PAINT BLUE (-1550 2300);
FORCEPROP 1 LASTPIN (-1600 2600) $PN 1
J 0
(-1590 2585);
DISPLAY 0.617021 (-1590 2585);
PAINT WHITE (-1590 2585);
FORCEPROP 2 LAST CDS_LIB mstr_discrete
J 0
(-1600 2500);
DISPLAY 1.617021 (-1600 2500);
PAINT ORANGE (-1600 2500);
DISPLAY INVISIBLE (-1600 2500);
FORCEPROP 2 LAST BOM_COST PVMCP_MCP_CPU0_VR
J 0
(-1550 2650);
DISPLAY 1.617021 (-1550 2650);
PAINT WHITE (-1550 2650);
DISPLAY INVISIBLE (-1550 2650);
FORCEPROP 2 LAST SEC_TYPE 3018
J 0
(-1545 2720);
DISPLAY 1.659574 (-1545 2720);
PAINT ORANGE (-1545 2720);
DISPLAY INVISIBLE (-1545 2720);
FORCEPROP 2 LAST SEC 1
J 0
(-1545 2720);
DISPLAY 1.106383 (-1545 2720);
PAINT MONO (-1545 2720);
DISPLAY INVISIBLE (-1545 2720);
FORCEPROP 2 LAST CDS_LOCATION C4R1
J 0
(-1550 2600);
DISPLAY 0.617021 (-1550 2600);
PAINT AQUA (-1550 2600);
DISPLAY INVISIBLE (-1550 2600);
FORCEPROP 1 LAST PATH I29
J 0
(-1550 2650);
DISPLAY 0.978723 (-1550 2650);
PAINT ORANGE (-1550 2650);
DISPLAY INVISIBLE (-1550 2650);
FORCEPROP 2 LAST ROOM PVMCP_MCP_CPU0_VR
J 0
(-1550 2625);
DISPLAY 1.617021 (-1550 2625);
PAINT WHITE (-1550 2625);
DISPLAY INVISIBLE (-1550 2625);
FORCEADD VCC_CORE..1
(-1900 2725);
FORCEPROP 3 LASTPIN (-1900 2675) SIG_NAME PVCCMCP_CPU0\g
J 0
(-1890 2685);
DISPLAY 0.659574 (-1890 2685);
PAINT MONO (-1890 2685);
DISPLAY INVISIBLE (-1890 2685);
FORCEPROP 1 LAST HDL_POWER PVCCMCP_CPU0
J 1
(-1900 2775);
DISPLAY 0.617021 (-1900 2775);
PAINT GREEN (-1900 2775);
FORCEPROP 2 LAST CDS_LIB mstr_symbols
J 0
(-1900 2725);
PAINT ORANGE (-1900 2725);
DISPLAY INVISIBLE (-1900 2725);
FORCEPROP 2 LAST BOM_COST PVMCP_FPGA_CPU0_VR
J 0
(-1900 2825);
DISPLAY 2.340426 (-1900 2825);
PAINT WHITE (-1900 2825);
DISPLAY INVISIBLE (-1900 2825);
FORCEPROP 1 LAST PATH I30
J 0
(-1850 2750);
DISPLAY 0.872340 (-1850 2750);
PAINT AQUA (-1850 2750);
DISPLAY INVISIBLE (-1850 2750);
FORCEPROP 2 LAST ROOM PVMCP_FPGA_CPU0_VR
J 0
(-1900 2825);
DISPLAY 3.127660 (-1900 2825);
PAINT WHITE (-1900 2825);
DISPLAY INVISIBLE (-1900 2825);
FORCEADD CAPP..1
(-1900 2500);
FORCEPROP 0 LAST GROUP PWR_MCP_CAP
J 0
(-1850 2250);
DISPLAY 0.638298 (-1850 2250);
PAINT BROWN (-1850 2250);
DISPLAY BOTH (-1850 2250);
FORCEPROP 1 LASTPIN (-1900 2600) $PN 1
J 0
(-1890 2585);
DISPLAY 0.617021 (-1890 2585);
PAINT WHITE (-1890 2585);
FORCEPROP 1 LASTPIN (-1900 2400) $PN 2
J 0
(-1890 2385);
DISPLAY 0.617021 (-1890 2385);
PAINT WHITE (-1890 2385);
FORCEPROP 1 LAST PACK_TYPE 3018
J 0
(-1850 2350);
DISPLAY 0.617021 (-1850 2350);
PAINT SKYBLUE (-1850 2350);
FORCEPROP 1 LAST TOLERANCE 20%
J 0
(-1850 2500);
DISPLAY 0.617021 (-1850 2500);
PAINT SKYBLUE (-1850 2500);
FORCEPROP 1 LAST LOCATION C3R4
J 0
(-1850 2600);
DISPLAY 0.617021 (-1850 2600);
PAINT AQUA (-1850 2600);
FORCEPROP 1 LAST PART_NUMBER 699013-049
J 0
(-1850 2300);
DISPLAY 0.617021 (-1850 2300);
PAINT BLUE (-1850 2300);
FORCEPROP 1 LAST VALUE 470UF
J 0
(-1850 2550);
DISPLAY 0.617021 (-1850 2550);
PAINT SKYBLUE (-1850 2550);
FORCEPROP 1 LAST VOLTAGE 2.5V
J 0
(-1850 2450);
DISPLAY 0.659574 (-1850 2450);
PAINT SKYBLUE (-1850 2450);
FORCEPROP 1 LAST MATERIAL ALUM
J 0
(-1850 2400);
DISPLAY 0.617021 (-1850 2400);
PAINT SKYBLUE (-1850 2400);
FORCEPROP 2 LAST ROOM PVMCP_MCP_CPU0_VR
J 0
(-1850 2625);
DISPLAY 1.617021 (-1850 2625);
PAINT WHITE (-1850 2625);
DISPLAY INVISIBLE (-1850 2625);
FORCEPROP 1 LAST PATH I31
J 0
(-1850 2650);
DISPLAY 0.978723 (-1850 2650);
PAINT ORANGE (-1850 2650);
DISPLAY INVISIBLE (-1850 2650);
FORCEPROP 2 LAST CDS_LOCATION C3R4
J 0
(-1850 2600);
DISPLAY 0.617021 (-1850 2600);
PAINT AQUA (-1850 2600);
DISPLAY INVISIBLE (-1850 2600);
FORCEPROP 2 LAST $SEC 1
J 0
(-1850 2700);
DISPLAY 1.617021 (-1850 2700);
PAINT MONO (-1850 2700);
DISPLAY INVISIBLE (-1850 2700);
FORCEPROP 2 LAST CDS_SEC 1
J 0
(-1850 2700);
DISPLAY 1.617021 (-1850 2700);
PAINT MONO (-1850 2700);
DISPLAY INVISIBLE (-1850 2700);
FORCEPROP 2 LAST BOM_COST PVMCP_MCP_CPU0_VR
J 0
(-1850 2650);
DISPLAY 1.617021 (-1850 2650);
PAINT WHITE (-1850 2650);
DISPLAY INVISIBLE (-1850 2650);
FORCEPROP 2 LAST CDS_LIB mstr_discrete
J 0
(-1900 2500);
DISPLAY 1.617021 (-1900 2500);
PAINT ORANGE (-1900 2500);
DISPLAY INVISIBLE (-1900 2500);
FORCEADD GND..1
(-1900 2225);
FORCEPROP 3 LASTPIN (-1900 2275) SIG_NAME GND\g
J 0
(-1890 2285);
DISPLAY 0.659574 (-1890 2285);
PAINT MONO (-1890 2285);
DISPLAY INVISIBLE (-1890 2285);
FORCEPROP 2 LAST ROOM PVMCP_FPGA_CPU0_VR
J 0
(-2450 2300);
DISPLAY 3.127660 (-2450 2300);
PAINT WHITE (-2450 2300);
DISPLAY INVISIBLE (-2450 2300);
FORCEPROP 1 LAST PATH I33
J 0
(-1825 2225);
DISPLAY 0.872340 (-1825 2225);
PAINT AQUA (-1825 2225);
DISPLAY INVISIBLE (-1825 2225);
FORCEPROP 2 LAST BOM_COST PVMCP_FPGA_CPU0_VR
J 0
(-2275 2300);
DISPLAY 2.340426 (-2275 2300);
PAINT WHITE (-2275 2300);
DISPLAY INVISIBLE (-2275 2300);
FORCEPROP 1 LAST SIZE 1B
J 0
(-1825 2175);
DISPLAY 2.787234 (-1825 2175);
PAINT GREEN (-1825 2175);
DISPLAY INVISIBLE (-1825 2175);
FORCEPROP 2 LAST CDS_LIB mstr_symbols
J 0
(-1900 2225);
DISPLAY 1.617021 (-1900 2225);
PAINT ORANGE (-1900 2225);
DISPLAY INVISIBLE (-1900 2225);
FORCEPROP 1 LAST VOLTAGE 0.0V
J 0
(-1945 2182);
DISPLAY 0.340426 (-1945 2182);
PAINT SKYBLUE (-1945 2182);
DISPLAY INVISIBLE (-1945 2182);
FORCEPROP 1 LAST BODY_TYPE PLUMBING
J 0
(-1945 2182);
DISPLAY 0.340426 (-1945 2182);
PAINT GREEN (-1945 2182);
DISPLAY INVISIBLE (-1945 2182);
FORCEPROP 1 LAST HDL_POWER GND
J 0
(-1900 2375);
DISPLAY 2.787234 (-1900 2375);
PAINT GREEN (-1900 2375);
DISPLAY INVISIBLE (-1900 2375);
FORCEADD SCONN120_H61426002..1
(-3150 2100);
FORCEPROP 2 LASTPIN (-2750 2700) $PN B14
J 0
(-2740 2710);
DISPLAY 0.617021 (-2740 2710);
PAINT ORANGE (-2740 2710);
FORCEPROP 2 LASTPIN (-2750 2600) $PN D14
J 0
(-2740 2610);
DISPLAY 0.617021 (-2740 2610);
PAINT ORANGE (-2740 2610);
FORCEPROP 2 LASTPIN (-2750 1350) $PN A18
J 0
(-2740 1360);
DISPLAY 0.617021 (-2740 1360);
PAINT ORANGE (-2740 1360);
FORCEPROP 2 LASTPIN (-2750 1300) $PN B18
J 0
(-2740 1310);
DISPLAY 0.617021 (-2740 1310);
PAINT ORANGE (-2740 1310);
FORCEPROP 2 LASTPIN (-2750 2150) $PN F15
J 0
(-2740 2160);
DISPLAY 0.617021 (-2740 2160);
PAINT ORANGE (-2740 2160);
FORCEPROP 2 LASTPIN (-2750 2250) $PN D15
J 0
(-2740 2260);
DISPLAY 0.617021 (-2740 2260);
PAINT ORANGE (-2740 2260);
FORCEPROP 2 LASTPIN (-3550 2900) $PN E3
J 2
(-3560 2910);
DISPLAY 0.617021 (-3560 2910);
PAINT ORANGE (-3560 2910);
FORCEPROP 2 LASTPIN (-2750 3250) $PN E12
J 0
(-2740 3260);
DISPLAY 0.617021 (-2740 3260);
PAINT ORANGE (-2740 3260);
FORCEPROP 1 LAST LOCATION J6E1
J 0
(-3500 4100);
DISPLAY 0.617021 (-3500 4100);
PAINT AQUA (-3500 4100);
FORCEPROP 1 LAST MATERIAL CONN
J 0
(-3500 4050);
DISPLAY 0.617021 (-3500 4050);
PAINT SKYBLUE (-3500 4050);
FORCEPROP 2 LASTPIN (-3550 3700) $PN C1
J 2
(-3560 3710);
DISPLAY 0.617021 (-3560 3710);
PAINT ORANGE (-3560 3710);
FORCEPROP 2 LASTPIN (-3550 3050) $PN B3
J 2
(-3560 3060);
DISPLAY 0.617021 (-3560 3060);
PAINT ORANGE (-3560 3060);
FORCEPROP 2 LASTPIN (-2750 3650) $PN D11
J 0
(-2740 3660);
DISPLAY 0.617021 (-2740 3660);
PAINT ORANGE (-2740 3660);
FORCEPROP 2 LASTPIN (-3550 3250) $PN E2
J 2
(-3560 3260);
DISPLAY 0.617021 (-3560 3260);
PAINT ORANGE (-3560 3260);
FORCEPROP 2 LASTPIN (-3550 3100) $PN A3
J 2
(-3560 3110);
DISPLAY 0.617021 (-3560 3110);
PAINT ORANGE (-3560 3110);
FORCEPROP 0 LAST ROOM MCP VRM CPU0
J 0
(-3375 4025);
DISPLAY 0.617021 (-3375 4025);
PAINT ORANGE (-3375 4025);
FORCEPROP 2 LASTPIN (-3550 3750) $PN B1
J 2
(-3560 3760);
DISPLAY 0.617021 (-3560 3760);
PAINT ORANGE (-3560 3760);
FORCEPROP 2 LASTPIN (-3550 2850) $PN F3
J 2
(-3560 2860);
DISPLAY 0.617021 (-3560 2860);
PAINT ORANGE (-3560 2860);
FORCEPROP 2 LASTPIN (-2750 3300) $PN D12
J 0
(-2740 3310);
DISPLAY 0.617021 (-2740 3310);
PAINT ORANGE (-2740 3310);
FORCEPROP 2 LASTPIN (-2750 500) $PN D20
J 0
(-2740 510);
DISPLAY 0.617021 (-2740 510);
PAINT ORANGE (-2740 510);
FORCEPROP 2 LASTPIN (-3550 2050) $PN A6
J 2
(-3560 2060);
DISPLAY 0.617021 (-3560 2060);
PAINT ORANGE (-3560 2060);
FORCEPROP 2 LASTPIN (-3550 2150) $PN F5
J 2
(-3560 2160);
DISPLAY 0.617021 (-3560 2160);
PAINT ORANGE (-3560 2160);
FORCEPROP 2 LASTPIN (-3550 2200) $PN E5
J 2
(-3560 2210);
DISPLAY 0.617021 (-3560 2210);
PAINT ORANGE (-3560 2210);
FORCEPROP 2 LASTPIN (-3550 2250) $PN D5
J 2
(-3560 2260);
DISPLAY 0.617021 (-3560 2260);
PAINT ORANGE (-3560 2260);
FORCEPROP 2 LASTPIN (-3550 2300) $PN C5
J 2
(-3560 2310);
DISPLAY 0.617021 (-3560 2310);
PAINT ORANGE (-3560 2310);
FORCEPROP 2 LASTPIN (-3550 2350) $PN B5
J 2
(-3560 2360);
DISPLAY 0.617021 (-3560 2360);
PAINT ORANGE (-3560 2360);
FORCEPROP 2 LASTPIN (-3550 2400) $PN A5
J 2
(-3560 2410);
DISPLAY 0.617021 (-3560 2410);
PAINT ORANGE (-3560 2410);
FORCEPROP 2 LASTPIN (-3550 1800) $PN F6
J 2
(-3560 1810);
DISPLAY 0.617021 (-3560 1810);
PAINT ORANGE (-3560 1810);
FORCEPROP 2 LASTPIN (-3550 1850) $PN E6
J 2
(-3560 1860);
DISPLAY 0.617021 (-3560 1860);
PAINT ORANGE (-3560 1860);
FORCEPROP 2 LASTPIN (-3550 1900) $PN D6
J 2
(-3560 1910);
DISPLAY 0.617021 (-3560 1910);
PAINT ORANGE (-3560 1910);
FORCEPROP 2 LASTPIN (-3550 1950) $PN C6
J 2
(-3560 1960);
DISPLAY 0.617021 (-3560 1960);
PAINT ORANGE (-3560 1960);
FORCEPROP 2 LASTPIN (-3550 2000) $PN B6
J 2
(-3560 2010);
DISPLAY 0.617021 (-3560 2010);
PAINT ORANGE (-3560 2010);
FORCEPROP 2 LASTPIN (-3550 1700) $PN A7
J 2
(-3560 1710);
DISPLAY 0.617021 (-3560 1710);
PAINT ORANGE (-3560 1710);
FORCEPROP 2 LASTPIN (-2750 1550) $PN D17
J 0
(-2740 1560);
DISPLAY 0.617021 (-2740 1560);
PAINT ORANGE (-2740 1560);
FORCEPROP 2 LASTPIN (-3550 1500) $PN E7
J 2
(-3560 1510);
DISPLAY 0.617021 (-3560 1510);
PAINT ORANGE (-3560 1510);
FORCEPROP 2 LASTPIN (-3550 3800) $PN A1
J 2
(-3560 3810);
DISPLAY 0.617021 (-3560 3810);
PAINT ORANGE (-3560 3810);
FORCEPROP 2 LASTPIN (-3550 3450) $PN A2
J 2
(-3560 3460);
DISPLAY 0.617021 (-3560 3460);
PAINT ORANGE (-3560 3460);
FORCEPROP 2 LASTPIN (-3550 2750) $PN A4
J 2
(-3560 2760);
DISPLAY 0.617021 (-3560 2760);
PAINT ORANGE (-3560 2760);
FORCEPROP 2 LASTPIN (-3550 1350) $PN A8
J 2
(-3560 1360);
DISPLAY 0.617021 (-3560 1360);
PAINT ORANGE (-3560 1360);
FORCEPROP 2 LASTPIN (-3550 1000) $PN A9
J 2
(-3560 1010);
DISPLAY 0.617021 (-3560 1010);
PAINT ORANGE (-3560 1010);
FORCEPROP 2 LASTPIN (-3550 650) $PN A10
J 2
(-3560 660);
DISPLAY 0.617021 (-3560 660);
PAINT ORANGE (-3560 660);
FORCEPROP 2 LASTPIN (-2750 3800) $PN A11
J 0
(-2740 3810);
DISPLAY 0.617021 (-2740 3810);
PAINT ORANGE (-2740 3810);
FORCEPROP 2 LASTPIN (-2750 3450) $PN A12
J 0
(-2740 3460);
DISPLAY 0.617021 (-2740 3460);
PAINT ORANGE (-2740 3460);
FORCEPROP 2 LASTPIN (-2750 3100) $PN A13
J 0
(-2740 3110);
DISPLAY 0.617021 (-2740 3110);
PAINT ORANGE (-2740 3110);
FORCEPROP 2 LASTPIN (-2750 2750) $PN A14
J 0
(-2740 2760);
DISPLAY 0.617021 (-2740 2760);
PAINT ORANGE (-2740 2760);
FORCEPROP 2 LASTPIN (-2750 2400) $PN A15
J 0
(-2740 2410);
DISPLAY 0.617021 (-2740 2410);
PAINT ORANGE (-2740 2410);
FORCEPROP 2 LASTPIN (-2750 2050) $PN A16
J 0
(-2740 2060);
DISPLAY 0.617021 (-2740 2060);
PAINT ORANGE (-2740 2060);
FORCEPROP 2 LASTPIN (-2750 1700) $PN A17
J 0
(-2740 1710);
DISPLAY 0.617021 (-2740 1710);
PAINT ORANGE (-2740 1710);
FORCEPROP 2 LASTPIN (-2750 1000) $PN A19
J 0
(-2740 1010);
DISPLAY 0.617021 (-2740 1010);
PAINT ORANGE (-2740 1010);
FORCEPROP 2 LASTPIN (-2750 650) $PN A20
J 0
(-2740 660);
DISPLAY 0.617021 (-2740 660);
PAINT ORANGE (-2740 660);
FORCEPROP 2 LASTPIN (-3550 3400) $PN B2
J 2
(-3560 3410);
DISPLAY 0.617021 (-3560 3410);
PAINT ORANGE (-3560 3410);
FORCEPROP 2 LASTPIN (-3550 2700) $PN B4
J 2
(-3560 2710);
DISPLAY 0.617021 (-3560 2710);
PAINT ORANGE (-3560 2710);
FORCEPROP 2 LASTPIN (-3550 1650) $PN B7
J 2
(-3560 1660);
DISPLAY 0.617021 (-3560 1660);
PAINT ORANGE (-3560 1660);
FORCEPROP 2 LASTPIN (-3550 1300) $PN B8
J 2
(-3560 1310);
DISPLAY 0.617021 (-3560 1310);
PAINT ORANGE (-3560 1310);
FORCEPROP 2 LASTPIN (-3550 950) $PN B9
J 2
(-3560 960);
DISPLAY 0.617021 (-3560 960);
PAINT ORANGE (-3560 960);
FORCEPROP 2 LASTPIN (-3550 600) $PN B10
J 2
(-3560 610);
DISPLAY 0.617021 (-3560 610);
PAINT ORANGE (-3560 610);
FORCEPROP 2 LASTPIN (-2750 3750) $PN B11
J 0
(-2740 3760);
DISPLAY 0.617021 (-2740 3760);
PAINT ORANGE (-2740 3760);
FORCEPROP 2 LASTPIN (-2750 3400) $PN B12
J 0
(-2740 3410);
DISPLAY 0.617021 (-2740 3410);
PAINT ORANGE (-2740 3410);
FORCEPROP 2 LASTPIN (-2750 3050) $PN B13
J 0
(-2740 3060);
DISPLAY 0.617021 (-2740 3060);
PAINT ORANGE (-2740 3060);
FORCEPROP 2 LASTPIN (-2750 2350) $PN B15
J 0
(-2740 2360);
DISPLAY 0.617021 (-2740 2360);
PAINT ORANGE (-2740 2360);
FORCEPROP 2 LASTPIN (-2750 1650) $PN B17
J 0
(-2740 1660);
DISPLAY 0.617021 (-2740 1660);
PAINT ORANGE (-2740 1660);
FORCEPROP 2 LASTPIN (-2750 600) $PN B20
J 0
(-2740 610);
DISPLAY 0.617021 (-2740 610);
PAINT ORANGE (-2740 610);
FORCEPROP 2 LASTPIN (-3550 3350) $PN C2
J 2
(-3560 3360);
DISPLAY 0.617021 (-3560 3360);
PAINT ORANGE (-3560 3360);
FORCEPROP 2 LASTPIN (-3550 3000) $PN C3
J 2
(-3560 3010);
DISPLAY 0.617021 (-3560 3010);
PAINT ORANGE (-3560 3010);
FORCEPROP 2 LASTPIN (-3550 2650) $PN C4
J 2
(-3560 2660);
DISPLAY 0.617021 (-3560 2660);
PAINT ORANGE (-3560 2660);
FORCEPROP 2 LASTPIN (-3550 1600) $PN C7
J 2
(-3560 1610);
DISPLAY 0.617021 (-3560 1610);
PAINT ORANGE (-3560 1610);
FORCEPROP 2 LASTPIN (-3550 1250) $PN C8
J 2
(-3560 1260);
DISPLAY 0.617021 (-3560 1260);
PAINT ORANGE (-3560 1260);
FORCEPROP 2 LASTPIN (-3550 900) $PN C9
J 2
(-3560 910);
DISPLAY 0.617021 (-3560 910);
PAINT ORANGE (-3560 910);
FORCEPROP 2 LASTPIN (-3550 550) $PN C10
J 2
(-3560 560);
DISPLAY 0.617021 (-3560 560);
PAINT ORANGE (-3560 560);
FORCEPROP 2 LASTPIN (-2750 3700) $PN C11
J 0
(-2740 3710);
DISPLAY 0.617021 (-2740 3710);
PAINT ORANGE (-2740 3710);
FORCEPROP 2 LASTPIN (-2750 3350) $PN C12
J 0
(-2740 3360);
DISPLAY 0.617021 (-2740 3360);
PAINT ORANGE (-2740 3360);
FORCEPROP 2 LASTPIN (-2750 3000) $PN C13
J 0
(-2740 3010);
DISPLAY 0.617021 (-2740 3010);
PAINT ORANGE (-2740 3010);
FORCEPROP 2 LASTPIN (-2750 2650) $PN C14
J 0
(-2740 2660);
DISPLAY 0.617021 (-2740 2660);
PAINT ORANGE (-2740 2660);
FORCEPROP 2 LASTPIN (-2750 2300) $PN C15
J 0
(-2740 2310);
DISPLAY 0.617021 (-2740 2310);
PAINT ORANGE (-2740 2310);
FORCEPROP 2 LASTPIN (-2750 1950) $PN C16
J 0
(-2740 1960);
DISPLAY 0.617021 (-2740 1960);
PAINT ORANGE (-2740 1960);
FORCEPROP 2 LASTPIN (-2750 1600) $PN C17
J 0
(-2740 1610);
DISPLAY 0.617021 (-2740 1610);
PAINT ORANGE (-2740 1610);
FORCEPROP 2 LASTPIN (-2750 1250) $PN C18
J 0
(-2740 1260);
DISPLAY 0.617021 (-2740 1260);
PAINT ORANGE (-2740 1260);
FORCEPROP 2 LASTPIN (-2750 900) $PN C19
J 0
(-2740 910);
DISPLAY 0.617021 (-2740 910);
PAINT ORANGE (-2740 910);
FORCEPROP 2 LASTPIN (-2750 550) $PN C20
J 0
(-2740 560);
DISPLAY 0.617021 (-2740 560);
PAINT ORANGE (-2740 560);
FORCEPROP 2 LASTPIN (-3550 3650) $PN D1
J 2
(-3560 3660);
DISPLAY 0.617021 (-3560 3660);
PAINT ORANGE (-3560 3660);
FORCEPROP 2 LASTPIN (-3550 3300) $PN D2
J 2
(-3560 3310);
DISPLAY 0.617021 (-3560 3310);
PAINT ORANGE (-3560 3310);
FORCEPROP 2 LASTPIN (-3550 2950) $PN D3
J 2
(-3560 2960);
DISPLAY 0.617021 (-3560 2960);
PAINT ORANGE (-3560 2960);
FORCEPROP 2 LASTPIN (-3550 2600) $PN D4
J 2
(-3560 2610);
DISPLAY 0.617021 (-3560 2610);
PAINT ORANGE (-3560 2610);
FORCEPROP 2 LASTPIN (-3550 1550) $PN D7
J 2
(-3560 1560);
DISPLAY 0.617021 (-3560 1560);
PAINT ORANGE (-3560 1560);
FORCEPROP 2 LASTPIN (-3550 1200) $PN D8
J 2
(-3560 1210);
DISPLAY 0.617021 (-3560 1210);
PAINT ORANGE (-3560 1210);
FORCEPROP 2 LASTPIN (-3550 850) $PN D9
J 2
(-3560 860);
DISPLAY 0.617021 (-3560 860);
PAINT ORANGE (-3560 860);
FORCEPROP 2 LASTPIN (-3550 500) $PN D10
J 2
(-3560 510);
DISPLAY 0.617021 (-3560 510);
PAINT ORANGE (-3560 510);
FORCEPROP 2 LASTPIN (-2750 2950) $PN D13
J 0
(-2740 2960);
DISPLAY 0.617021 (-2740 2960);
PAINT ORANGE (-2740 2960);
FORCEPROP 2 LASTPIN (-2750 1900) $PN D16
J 0
(-2740 1910);
DISPLAY 0.617021 (-2740 1910);
PAINT ORANGE (-2740 1910);
FORCEPROP 2 LASTPIN (-2750 1200) $PN D18
J 0
(-2740 1210);
DISPLAY 0.617021 (-2740 1210);
PAINT ORANGE (-2740 1210);
FORCEPROP 2 LASTPIN (-2750 850) $PN D19
J 0
(-2740 860);
DISPLAY 0.617021 (-2740 860);
PAINT ORANGE (-2740 860);
FORCEPROP 2 LASTPIN (-3550 3600) $PN E1
J 2
(-3560 3610);
DISPLAY 0.617021 (-3560 3610);
PAINT ORANGE (-3560 3610);
FORCEPROP 2 LASTPIN (-3550 2550) $PN E4
J 2
(-3560 2560);
DISPLAY 0.617021 (-3560 2560);
PAINT ORANGE (-3560 2560);
FORCEPROP 2 LASTPIN (-3550 1150) $PN E8
J 2
(-3560 1160);
DISPLAY 0.617021 (-3560 1160);
PAINT ORANGE (-3560 1160);
FORCEPROP 2 LASTPIN (-3550 800) $PN E9
J 2
(-3560 810);
DISPLAY 0.617021 (-3560 810);
PAINT ORANGE (-3560 810);
FORCEPROP 2 LASTPIN (-3550 450) $PN E10
J 2
(-3560 460);
DISPLAY 0.617021 (-3560 460);
PAINT ORANGE (-3560 460);
FORCEPROP 2 LASTPIN (-2750 3600) $PN E11
J 0
(-2740 3610);
DISPLAY 0.617021 (-2740 3610);
PAINT ORANGE (-2740 3610);
FORCEPROP 2 LASTPIN (-2750 2900) $PN E13
J 0
(-2740 2910);
DISPLAY 0.617021 (-2740 2910);
PAINT ORANGE (-2740 2910);
FORCEPROP 2 LASTPIN (-2750 2550) $PN E14
J 0
(-2740 2560);
DISPLAY 0.617021 (-2740 2560);
PAINT ORANGE (-2740 2560);
FORCEPROP 2 LASTPIN (-2750 2200) $PN E15
J 0
(-2740 2210);
DISPLAY 0.617021 (-2740 2210);
PAINT ORANGE (-2740 2210);
FORCEPROP 2 LASTPIN (-2750 1850) $PN E16
J 0
(-2740 1860);
DISPLAY 0.617021 (-2740 1860);
PAINT ORANGE (-2740 1860);
FORCEPROP 2 LASTPIN (-2750 1150) $PN E18
J 0
(-2740 1160);
DISPLAY 0.617021 (-2740 1160);
PAINT ORANGE (-2740 1160);
FORCEPROP 2 LASTPIN (-2750 800) $PN E19
J 0
(-2740 810);
DISPLAY 0.617021 (-2740 810);
PAINT ORANGE (-2740 810);
FORCEPROP 2 LASTPIN (-2750 450) $PN E20
J 0
(-2740 460);
DISPLAY 0.617021 (-2740 460);
PAINT ORANGE (-2740 460);
FORCEPROP 2 LASTPIN (-3550 3550) $PN F1
J 2
(-3560 3560);
DISPLAY 0.617021 (-3560 3560);
PAINT ORANGE (-3560 3560);
FORCEPROP 2 LASTPIN (-3550 3200) $PN F2
J 2
(-3560 3210);
DISPLAY 0.617021 (-3560 3210);
PAINT ORANGE (-3560 3210);
FORCEPROP 2 LASTPIN (-3550 2500) $PN F4
J 2
(-3560 2510);
DISPLAY 0.617021 (-3560 2510);
PAINT ORANGE (-3560 2510);
FORCEPROP 2 LASTPIN (-3550 1450) $PN F7
J 2
(-3560 1460);
DISPLAY 0.617021 (-3560 1460);
PAINT ORANGE (-3560 1460);
FORCEPROP 2 LASTPIN (-3550 1100) $PN F8
J 2
(-3560 1110);
DISPLAY 0.617021 (-3560 1110);
PAINT ORANGE (-3560 1110);
FORCEPROP 2 LASTPIN (-3550 750) $PN F9
J 2
(-3560 760);
DISPLAY 0.617021 (-3560 760);
PAINT ORANGE (-3560 760);
FORCEPROP 2 LASTPIN (-3550 400) $PN F10
J 2
(-3560 410);
DISPLAY 0.617021 (-3560 410);
PAINT ORANGE (-3560 410);
FORCEPROP 2 LASTPIN (-2750 3550) $PN F11
J 0
(-2740 3560);
DISPLAY 0.617021 (-2740 3560);
PAINT ORANGE (-2740 3560);
FORCEPROP 2 LASTPIN (-2750 3200) $PN F12
J 0
(-2740 3210);
DISPLAY 0.617021 (-2740 3210);
PAINT ORANGE (-2740 3210);
FORCEPROP 2 LASTPIN (-2750 2850) $PN F13
J 0
(-2740 2860);
DISPLAY 0.617021 (-2740 2860);
PAINT ORANGE (-2740 2860);
FORCEPROP 2 LASTPIN (-2750 2500) $PN F14
J 0
(-2740 2510);
DISPLAY 0.617021 (-2740 2510);
PAINT ORANGE (-2740 2510);
FORCEPROP 2 LASTPIN (-2750 1800) $PN F16
J 0
(-2740 1810);
DISPLAY 0.617021 (-2740 1810);
PAINT ORANGE (-2740 1810);
FORCEPROP 2 LASTPIN (-2750 1450) $PN F17
J 0
(-2740 1460);
DISPLAY 0.617021 (-2740 1460);
PAINT ORANGE (-2740 1460);
FORCEPROP 2 LASTPIN (-2750 1100) $PN F18
J 0
(-2740 1110);
DISPLAY 0.617021 (-2740 1110);
PAINT ORANGE (-2740 1110);
FORCEPROP 2 LASTPIN (-2750 400) $PN F20
J 0
(-2740 410);
DISPLAY 0.617021 (-2740 410);
PAINT ORANGE (-2740 410);
FORCEPROP 2 LASTPIN (-2750 2000) $PN B16
J 0
(-2740 2010);
DISPLAY 0.617021 (-2740 2010);
PAINT ORANGE (-2740 2010);
FORCEPROP 2 LASTPIN (-2750 750) $PN F19
J 0
(-2740 760);
DISPLAY 0.617021 (-2740 760);
PAINT ORANGE (-2740 760);
FORCEPROP 2 LASTPIN (-2750 1500) $PN E17
J 0
(-2740 1510);
DISPLAY 0.617021 (-2740 1510);
PAINT ORANGE (-2740 1510);
FORCEPROP 1 LAST PART_NUMBER H61426-002
J 0
(-3500 250);
DISPLAY 0.617021 (-3500 250);
PAINT BLUE (-3500 250);
FORCEPROP 2 LASTPIN (-2750 950) $PN B19
J 0
(-2740 960);
DISPLAY 0.617021 (-2740 960);
PAINT ORANGE (-2740 960);
FORCEPROP 0 LAST GROUP MCP
J 0
(-3500 200);
DISPLAY 0.638298 (-3500 200);
PAINT BROWN (-3500 200);
DISPLAY BOTH (-3500 200);
FORCEPROP 1 LAST PATH I55
J 0
(-3100 4050);
PAINT GREEN (-3100 4050);
DISPLAY INVISIBLE (-3100 4050);
FORCEPROP 2 LAST CDS_LOCATION J6E1
J 0
(-3500 4100);
DISPLAY 0.617021 (-3500 4100);
PAINT AQUA (-3500 4100);
DISPLAY INVISIBLE (-3500 4100);
FORCEPROP 2 LAST SEC 1
J 0
(-3500 4150);
DISPLAY 0.680851 (-3500 4150);
PAINT MONO (-3500 4150);
DISPLAY INVISIBLE (-3500 4150);
FORCEPROP 2 LAST CDS_LIB mstr_sconn
J 0
(-3150 2100);
PAINT ORANGE (-3150 2100);
DISPLAY INVISIBLE (-3150 2100);
FORCEPROP 2 LAST SEC_TYPE SM
J 0
(-3500 4150);
DISPLAY 1.021277 (-3500 4150);
PAINT ORANGE (-3500 4150);
DISPLAY INVISIBLE (-3500 4150);
FORCEPROP 1 LAST PACK_TYPE SM
J 0
(-3500 4150);
PAINT SKYBLUE (-3500 4150);
DISPLAY INVISIBLE (-3500 4150);
FORCEADD SCONN120_H61426002..1
(-6550 2075);
FORCEPROP 2 LASTPIN (-6150 475) $PN D20
J 0
(-6140 485);
DISPLAY 0.617021 (-6140 485);
PAINT ORANGE (-6140 485);
FORCEPROP 2 LASTPIN (-6150 525) $PN C20
J 0
(-6140 535);
DISPLAY 0.617021 (-6140 535);
PAINT ORANGE (-6140 535);
FORCEPROP 2 LASTPIN (-6950 3775) $PN A1
J 2
(-6960 3785);
DISPLAY 0.617021 (-6960 3785);
PAINT ORANGE (-6960 3785);
FORCEPROP 2 LASTPIN (-6950 3675) $PN C1
J 2
(-6960 3685);
DISPLAY 0.617021 (-6960 3685);
PAINT ORANGE (-6960 3685);
FORCEPROP 2 LASTPIN (-6950 3625) $PN D1
J 2
(-6960 3635);
DISPLAY 0.617021 (-6960 3635);
PAINT ORANGE (-6960 3635);
FORCEPROP 2 LASTPIN (-6150 3075) $PN A13
J 0
(-6140 3085);
DISPLAY 0.617021 (-6140 3085);
PAINT ORANGE (-6140 3085);
FORCEPROP 2 LASTPIN (-6150 3175) $PN F12
J 0
(-6140 3185);
DISPLAY 0.617021 (-6140 3185);
PAINT ORANGE (-6140 3185);
FORCEPROP 2 LASTPIN (-6150 2975) $PN C13
J 0
(-6140 2985);
DISPLAY 0.617021 (-6140 2985);
PAINT ORANGE (-6140 2985);
FORCEPROP 0 LAST ROOM MCP VRM CPU0
J 0
(-6725 4000);
DISPLAY 0.617021 (-6725 4000);
PAINT ORANGE (-6725 4000);
FORCEPROP 2 LASTPIN (-6150 2725) $PN A14
J 0
(-6140 2735);
DISPLAY 0.617021 (-6140 2735);
PAINT ORANGE (-6140 2735);
FORCEPROP 2 LASTPIN (-6150 2225) $PN D15
J 0
(-6140 2235);
DISPLAY 0.617021 (-6140 2235);
PAINT ORANGE (-6140 2235);
FORCEPROP 2 LASTPIN (-6150 2175) $PN E15
J 0
(-6140 2185);
DISPLAY 0.617021 (-6140 2185);
PAINT ORANGE (-6140 2185);
FORCEPROP 2 LASTPIN (-6150 2575) $PN D14
J 0
(-6140 2585);
DISPLAY 0.617021 (-6140 2585);
PAINT ORANGE (-6140 2585);
FORCEPROP 2 LASTPIN (-6150 2625) $PN C14
J 0
(-6140 2635);
DISPLAY 0.617021 (-6140 2635);
PAINT ORANGE (-6140 2635);
FORCEPROP 2 LASTPIN (-6150 2675) $PN B14
J 0
(-6140 2685);
DISPLAY 0.617021 (-6140 2685);
PAINT ORANGE (-6140 2685);
FORCEPROP 2 LASTPIN (-6150 1825) $PN E16
J 0
(-6140 1835);
DISPLAY 0.617021 (-6140 1835);
PAINT ORANGE (-6140 1835);
FORCEPROP 2 LASTPIN (-6150 1875) $PN D16
J 0
(-6140 1885);
DISPLAY 0.617021 (-6140 1885);
PAINT ORANGE (-6140 1885);
FORCEPROP 2 LASTPIN (-6150 1925) $PN C16
J 0
(-6140 1935);
DISPLAY 0.617021 (-6140 1935);
PAINT ORANGE (-6140 1935);
FORCEPROP 2 LASTPIN (-6150 1975) $PN B16
J 0
(-6140 1985);
DISPLAY 0.617021 (-6140 1985);
PAINT ORANGE (-6140 1985);
FORCEPROP 2 LASTPIN (-6150 2025) $PN A16
J 0
(-6140 2035);
DISPLAY 0.617021 (-6140 2035);
PAINT ORANGE (-6140 2035);
FORCEPROP 2 LASTPIN (-6150 2275) $PN C15
J 0
(-6140 2285);
DISPLAY 0.617021 (-6140 2285);
PAINT ORANGE (-6140 2285);
FORCEPROP 2 LASTPIN (-6150 2325) $PN B15
J 0
(-6140 2335);
DISPLAY 0.617021 (-6140 2335);
PAINT ORANGE (-6140 2335);
FORCEPROP 2 LASTPIN (-6150 2375) $PN A15
J 0
(-6140 2385);
DISPLAY 0.617021 (-6140 2385);
PAINT ORANGE (-6140 2385);
FORCEPROP 2 LASTPIN (-6150 2475) $PN F14
J 0
(-6140 2485);
DISPLAY 0.617021 (-6140 2485);
PAINT ORANGE (-6140 2485);
FORCEPROP 2 LASTPIN (-6150 2525) $PN E14
J 0
(-6140 2535);
DISPLAY 0.617021 (-6140 2535);
PAINT ORANGE (-6140 2535);
FORCEPROP 2 LASTPIN (-6150 2825) $PN F13
J 0
(-6140 2835);
DISPLAY 0.617021 (-6140 2835);
PAINT ORANGE (-6140 2835);
FORCEPROP 2 LASTPIN (-6150 2875) $PN E13
J 0
(-6140 2885);
DISPLAY 0.617021 (-6140 2885);
PAINT ORANGE (-6140 2885);
FORCEPROP 2 LASTPIN (-6950 3425) $PN A2
J 2
(-6960 3435);
DISPLAY 0.617021 (-6960 3435);
PAINT ORANGE (-6960 3435);
FORCEPROP 2 LASTPIN (-6950 3075) $PN A3
J 2
(-6960 3085);
DISPLAY 0.617021 (-6960 3085);
PAINT ORANGE (-6960 3085);
FORCEPROP 2 LASTPIN (-6950 2725) $PN A4
J 2
(-6960 2735);
DISPLAY 0.617021 (-6960 2735);
PAINT ORANGE (-6960 2735);
FORCEPROP 2 LASTPIN (-6950 2375) $PN A5
J 2
(-6960 2385);
DISPLAY 0.617021 (-6960 2385);
PAINT ORANGE (-6960 2385);
FORCEPROP 2 LASTPIN (-6950 2025) $PN A6
J 2
(-6960 2035);
DISPLAY 0.617021 (-6960 2035);
PAINT ORANGE (-6960 2035);
FORCEPROP 2 LASTPIN (-6950 1675) $PN A7
J 2
(-6960 1685);
DISPLAY 0.617021 (-6960 1685);
PAINT ORANGE (-6960 1685);
FORCEPROP 2 LASTPIN (-6950 1325) $PN A8
J 2
(-6960 1335);
DISPLAY 0.617021 (-6960 1335);
PAINT ORANGE (-6960 1335);
FORCEPROP 2 LASTPIN (-6950 975) $PN A9
J 2
(-6960 985);
DISPLAY 0.617021 (-6960 985);
PAINT ORANGE (-6960 985);
FORCEPROP 2 LASTPIN (-6950 625) $PN A10
J 2
(-6960 635);
DISPLAY 0.617021 (-6960 635);
PAINT ORANGE (-6960 635);
FORCEPROP 2 LASTPIN (-6150 3775) $PN A11
J 0
(-6140 3785);
DISPLAY 0.617021 (-6140 3785);
PAINT ORANGE (-6140 3785);
FORCEPROP 2 LASTPIN (-6150 3425) $PN A12
J 0
(-6140 3435);
DISPLAY 0.617021 (-6140 3435);
PAINT ORANGE (-6140 3435);
FORCEPROP 2 LASTPIN (-6150 1325) $PN A18
J 0
(-6140 1335);
DISPLAY 0.617021 (-6140 1335);
PAINT ORANGE (-6140 1335);
FORCEPROP 2 LASTPIN (-6150 975) $PN A19
J 0
(-6140 985);
DISPLAY 0.617021 (-6140 985);
PAINT ORANGE (-6140 985);
FORCEPROP 2 LASTPIN (-6150 625) $PN A20
J 0
(-6140 635);
DISPLAY 0.617021 (-6140 635);
PAINT ORANGE (-6140 635);
FORCEPROP 2 LASTPIN (-6950 3725) $PN B1
J 2
(-6960 3735);
DISPLAY 0.617021 (-6960 3735);
PAINT ORANGE (-6960 3735);
FORCEPROP 2 LASTPIN (-6950 3375) $PN B2
J 2
(-6960 3385);
DISPLAY 0.617021 (-6960 3385);
PAINT ORANGE (-6960 3385);
FORCEPROP 2 LASTPIN (-6950 3025) $PN B3
J 2
(-6960 3035);
DISPLAY 0.617021 (-6960 3035);
PAINT ORANGE (-6960 3035);
FORCEPROP 2 LASTPIN (-6950 2675) $PN B4
J 2
(-6960 2685);
DISPLAY 0.617021 (-6960 2685);
PAINT ORANGE (-6960 2685);
FORCEPROP 2 LASTPIN (-6950 2325) $PN B5
J 2
(-6960 2335);
DISPLAY 0.617021 (-6960 2335);
PAINT ORANGE (-6960 2335);
FORCEPROP 2 LASTPIN (-6950 1975) $PN B6
J 2
(-6960 1985);
DISPLAY 0.617021 (-6960 1985);
PAINT ORANGE (-6960 1985);
FORCEPROP 2 LASTPIN (-6950 1625) $PN B7
J 2
(-6960 1635);
DISPLAY 0.617021 (-6960 1635);
PAINT ORANGE (-6960 1635);
FORCEPROP 2 LASTPIN (-6950 1275) $PN B8
J 2
(-6960 1285);
DISPLAY 0.617021 (-6960 1285);
PAINT ORANGE (-6960 1285);
FORCEPROP 2 LASTPIN (-6950 925) $PN B9
J 2
(-6960 935);
DISPLAY 0.617021 (-6960 935);
PAINT ORANGE (-6960 935);
FORCEPROP 2 LASTPIN (-6150 3725) $PN B11
J 0
(-6140 3735);
DISPLAY 0.617021 (-6140 3735);
PAINT ORANGE (-6140 3735);
FORCEPROP 2 LASTPIN (-6150 3375) $PN B12
J 0
(-6140 3385);
DISPLAY 0.617021 (-6140 3385);
PAINT ORANGE (-6140 3385);
FORCEPROP 2 LASTPIN (-6150 3025) $PN B13
J 0
(-6140 3035);
DISPLAY 0.617021 (-6140 3035);
PAINT ORANGE (-6140 3035);
FORCEPROP 2 LASTPIN (-6150 1625) $PN B17
J 0
(-6140 1635);
DISPLAY 0.617021 (-6140 1635);
PAINT ORANGE (-6140 1635);
FORCEPROP 2 LASTPIN (-6150 1275) $PN B18
J 0
(-6140 1285);
DISPLAY 0.617021 (-6140 1285);
PAINT ORANGE (-6140 1285);
FORCEPROP 2 LASTPIN (-6150 925) $PN B19
J 0
(-6140 935);
DISPLAY 0.617021 (-6140 935);
PAINT ORANGE (-6140 935);
FORCEPROP 2 LASTPIN (-6150 575) $PN B20
J 0
(-6140 585);
DISPLAY 0.617021 (-6140 585);
PAINT ORANGE (-6140 585);
FORCEPROP 2 LASTPIN (-6950 3325) $PN C2
J 2
(-6960 3335);
DISPLAY 0.617021 (-6960 3335);
PAINT ORANGE (-6960 3335);
FORCEPROP 2 LASTPIN (-6950 2975) $PN C3
J 2
(-6960 2985);
DISPLAY 0.617021 (-6960 2985);
PAINT ORANGE (-6960 2985);
FORCEPROP 2 LASTPIN (-6950 2625) $PN C4
J 2
(-6960 2635);
DISPLAY 0.617021 (-6960 2635);
PAINT ORANGE (-6960 2635);
FORCEPROP 2 LASTPIN (-6950 2275) $PN C5
J 2
(-6960 2285);
DISPLAY 0.617021 (-6960 2285);
PAINT ORANGE (-6960 2285);
FORCEPROP 2 LASTPIN (-6950 1925) $PN C6
J 2
(-6960 1935);
DISPLAY 0.617021 (-6960 1935);
PAINT ORANGE (-6960 1935);
FORCEPROP 2 LASTPIN (-6950 1575) $PN C7
J 2
(-6960 1585);
DISPLAY 0.617021 (-6960 1585);
PAINT ORANGE (-6960 1585);
FORCEPROP 2 LASTPIN (-6950 1225) $PN C8
J 2
(-6960 1235);
DISPLAY 0.617021 (-6960 1235);
PAINT ORANGE (-6960 1235);
FORCEPROP 2 LASTPIN (-6950 875) $PN C9
J 2
(-6960 885);
DISPLAY 0.617021 (-6960 885);
PAINT ORANGE (-6960 885);
FORCEPROP 2 LASTPIN (-6150 3675) $PN C11
J 0
(-6140 3685);
DISPLAY 0.617021 (-6140 3685);
PAINT ORANGE (-6140 3685);
FORCEPROP 2 LASTPIN (-6150 3325) $PN C12
J 0
(-6140 3335);
DISPLAY 0.617021 (-6140 3335);
PAINT ORANGE (-6140 3335);
FORCEPROP 2 LASTPIN (-6150 1575) $PN C17
J 0
(-6140 1585);
DISPLAY 0.617021 (-6140 1585);
PAINT ORANGE (-6140 1585);
FORCEPROP 2 LASTPIN (-6150 1225) $PN C18
J 0
(-6140 1235);
DISPLAY 0.617021 (-6140 1235);
PAINT ORANGE (-6140 1235);
FORCEPROP 2 LASTPIN (-6150 875) $PN C19
J 0
(-6140 885);
DISPLAY 0.617021 (-6140 885);
PAINT ORANGE (-6140 885);
FORCEPROP 2 LASTPIN (-6950 3275) $PN D2
J 2
(-6960 3285);
DISPLAY 0.617021 (-6960 3285);
PAINT ORANGE (-6960 3285);
FORCEPROP 2 LASTPIN (-6950 2925) $PN D3
J 2
(-6960 2935);
DISPLAY 0.617021 (-6960 2935);
PAINT ORANGE (-6960 2935);
FORCEPROP 2 LASTPIN (-6950 2575) $PN D4
J 2
(-6960 2585);
DISPLAY 0.617021 (-6960 2585);
PAINT ORANGE (-6960 2585);
FORCEPROP 2 LASTPIN (-6950 2225) $PN D5
J 2
(-6960 2235);
DISPLAY 0.617021 (-6960 2235);
PAINT ORANGE (-6960 2235);
FORCEPROP 2 LASTPIN (-6950 1875) $PN D6
J 2
(-6960 1885);
DISPLAY 0.617021 (-6960 1885);
PAINT ORANGE (-6960 1885);
FORCEPROP 2 LASTPIN (-6950 1525) $PN D7
J 2
(-6960 1535);
DISPLAY 0.617021 (-6960 1535);
PAINT ORANGE (-6960 1535);
FORCEPROP 2 LASTPIN (-6950 1175) $PN D8
J 2
(-6960 1185);
DISPLAY 0.617021 (-6960 1185);
PAINT ORANGE (-6960 1185);
FORCEPROP 2 LASTPIN (-6950 825) $PN D9
J 2
(-6960 835);
DISPLAY 0.617021 (-6960 835);
PAINT ORANGE (-6960 835);
FORCEPROP 2 LASTPIN (-6150 3625) $PN D11
J 0
(-6140 3635);
DISPLAY 0.617021 (-6140 3635);
PAINT ORANGE (-6140 3635);
FORCEPROP 2 LASTPIN (-6150 3275) $PN D12
J 0
(-6140 3285);
DISPLAY 0.617021 (-6140 3285);
PAINT ORANGE (-6140 3285);
FORCEPROP 2 LASTPIN (-6150 2925) $PN D13
J 0
(-6140 2935);
DISPLAY 0.617021 (-6140 2935);
PAINT ORANGE (-6140 2935);
FORCEPROP 2 LASTPIN (-6150 1525) $PN D17
J 0
(-6140 1535);
DISPLAY 0.617021 (-6140 1535);
PAINT ORANGE (-6140 1535);
FORCEPROP 2 LASTPIN (-6150 1175) $PN D18
J 0
(-6140 1185);
DISPLAY 0.617021 (-6140 1185);
PAINT ORANGE (-6140 1185);
FORCEPROP 2 LASTPIN (-6150 825) $PN D19
J 0
(-6140 835);
DISPLAY 0.617021 (-6140 835);
PAINT ORANGE (-6140 835);
FORCEPROP 2 LASTPIN (-6950 3575) $PN E1
J 2
(-6960 3585);
DISPLAY 0.617021 (-6960 3585);
PAINT ORANGE (-6960 3585);
FORCEPROP 2 LASTPIN (-6950 3225) $PN E2
J 2
(-6960 3235);
DISPLAY 0.617021 (-6960 3235);
PAINT ORANGE (-6960 3235);
FORCEPROP 2 LASTPIN (-6950 2875) $PN E3
J 2
(-6960 2885);
DISPLAY 0.617021 (-6960 2885);
PAINT ORANGE (-6960 2885);
FORCEPROP 2 LASTPIN (-6950 2525) $PN E4
J 2
(-6960 2535);
DISPLAY 0.617021 (-6960 2535);
PAINT ORANGE (-6960 2535);
FORCEPROP 2 LASTPIN (-6950 2175) $PN E5
J 2
(-6960 2185);
DISPLAY 0.617021 (-6960 2185);
PAINT ORANGE (-6960 2185);
FORCEPROP 2 LASTPIN (-6950 1825) $PN E6
J 2
(-6960 1835);
DISPLAY 0.617021 (-6960 1835);
PAINT ORANGE (-6960 1835);
FORCEPROP 2 LASTPIN (-6950 1475) $PN E7
J 2
(-6960 1485);
DISPLAY 0.617021 (-6960 1485);
PAINT ORANGE (-6960 1485);
FORCEPROP 2 LASTPIN (-6950 1125) $PN E8
J 2
(-6960 1135);
DISPLAY 0.617021 (-6960 1135);
PAINT ORANGE (-6960 1135);
FORCEPROP 2 LASTPIN (-6150 3575) $PN E11
J 0
(-6140 3585);
DISPLAY 0.617021 (-6140 3585);
PAINT ORANGE (-6140 3585);
FORCEPROP 2 LASTPIN (-6150 3225) $PN E12
J 0
(-6140 3235);
DISPLAY 0.617021 (-6140 3235);
PAINT ORANGE (-6140 3235);
FORCEPROP 2 LASTPIN (-6150 1125) $PN E18
J 0
(-6140 1135);
DISPLAY 0.617021 (-6140 1135);
PAINT ORANGE (-6140 1135);
FORCEPROP 2 LASTPIN (-6150 775) $PN E19
J 0
(-6140 785);
DISPLAY 0.617021 (-6140 785);
PAINT ORANGE (-6140 785);
FORCEPROP 2 LASTPIN (-6150 425) $PN E20
J 0
(-6140 435);
DISPLAY 0.617021 (-6140 435);
PAINT ORANGE (-6140 435);
FORCEPROP 2 LASTPIN (-6950 3525) $PN F1
J 2
(-6960 3535);
DISPLAY 0.617021 (-6960 3535);
PAINT ORANGE (-6960 3535);
FORCEPROP 2 LASTPIN (-6950 3175) $PN F2
J 2
(-6960 3185);
DISPLAY 0.617021 (-6960 3185);
PAINT ORANGE (-6960 3185);
FORCEPROP 2 LASTPIN (-6950 2825) $PN F3
J 2
(-6960 2835);
DISPLAY 0.617021 (-6960 2835);
PAINT ORANGE (-6960 2835);
FORCEPROP 2 LASTPIN (-6950 2475) $PN F4
J 2
(-6960 2485);
DISPLAY 0.617021 (-6960 2485);
PAINT ORANGE (-6960 2485);
FORCEPROP 2 LASTPIN (-6950 2125) $PN F5
J 2
(-6960 2135);
DISPLAY 0.617021 (-6960 2135);
PAINT ORANGE (-6960 2135);
FORCEPROP 2 LASTPIN (-6950 1775) $PN F6
J 2
(-6960 1785);
DISPLAY 0.617021 (-6960 1785);
PAINT ORANGE (-6960 1785);
FORCEPROP 2 LASTPIN (-6950 1425) $PN F7
J 2
(-6960 1435);
DISPLAY 0.617021 (-6960 1435);
PAINT ORANGE (-6960 1435);
FORCEPROP 2 LASTPIN (-6950 1075) $PN F8
J 2
(-6960 1085);
DISPLAY 0.617021 (-6960 1085);
PAINT ORANGE (-6960 1085);
FORCEPROP 2 LASTPIN (-6950 725) $PN F9
J 2
(-6960 735);
DISPLAY 0.617021 (-6960 735);
PAINT ORANGE (-6960 735);
FORCEPROP 2 LASTPIN (-6150 3525) $PN F11
J 0
(-6140 3535);
DISPLAY 0.617021 (-6140 3535);
PAINT ORANGE (-6140 3535);
FORCEPROP 2 LASTPIN (-6150 2125) $PN F15
J 0
(-6140 2135);
DISPLAY 0.617021 (-6140 2135);
PAINT ORANGE (-6140 2135);
FORCEPROP 2 LASTPIN (-6150 1775) $PN F16
J 0
(-6140 1785);
DISPLAY 0.617021 (-6140 1785);
PAINT ORANGE (-6140 1785);
FORCEPROP 2 LASTPIN (-6150 1075) $PN F18
J 0
(-6140 1085);
DISPLAY 0.617021 (-6140 1085);
PAINT ORANGE (-6140 1085);
FORCEPROP 2 LASTPIN (-6150 725) $PN F19
J 0
(-6140 735);
DISPLAY 0.617021 (-6140 735);
PAINT ORANGE (-6140 735);
FORCEPROP 1 LAST MATERIAL CONN
J 0
(-6900 4025);
DISPLAY 0.617021 (-6900 4025);
PAINT SKYBLUE (-6900 4025);
FORCEPROP 1 LAST LOCATION J6B1
J 0
(-6900 4075);
DISPLAY 0.617021 (-6900 4075);
PAINT AQUA (-6900 4075);
FORCEPROP 2 LASTPIN (-6950 575) $PN B10
J 2
(-6960 585);
DISPLAY 0.617021 (-6960 585);
PAINT ORANGE (-6960 585);
FORCEPROP 2 LASTPIN (-6950 425) $PN E10
J 2
(-6960 435);
DISPLAY 0.617021 (-6960 435);
PAINT ORANGE (-6960 435);
FORCEPROP 2 LASTPIN (-6150 1425) $PN F17
J 0
(-6140 1435);
DISPLAY 0.617021 (-6140 1435);
PAINT ORANGE (-6140 1435);
FORCEPROP 2 LASTPIN (-6150 1475) $PN E17
J 0
(-6140 1485);
DISPLAY 0.617021 (-6140 1485);
PAINT ORANGE (-6140 1485);
FORCEPROP 2 LASTPIN (-6150 1675) $PN A17
J 0
(-6140 1685);
DISPLAY 0.617021 (-6140 1685);
PAINT ORANGE (-6140 1685);
FORCEPROP 2 LASTPIN (-6150 375) $PN F20
J 0
(-6140 385);
DISPLAY 0.617021 (-6140 385);
PAINT ORANGE (-6140 385);
FORCEPROP 0 LAST GROUP MCP
J 0
(-6900 175);
DISPLAY 0.638298 (-6900 175);
PAINT BROWN (-6900 175);
DISPLAY BOTH (-6900 175);
FORCEPROP 1 LAST PART_NUMBER H61426-002
J 0
(-6900 225);
DISPLAY 0.617021 (-6900 225);
PAINT BLUE (-6900 225);
FORCEPROP 2 LASTPIN (-6950 375) $PN F10
J 2
(-6960 385);
DISPLAY 0.617021 (-6960 385);
PAINT ORANGE (-6960 385);
FORCEPROP 2 LASTPIN (-6950 475) $PN D10
J 2
(-6960 485);
DISPLAY 0.617021 (-6960 485);
PAINT ORANGE (-6960 485);
FORCEPROP 2 LASTPIN (-6950 525) $PN C10
J 2
(-6960 535);
DISPLAY 0.617021 (-6960 535);
PAINT ORANGE (-6960 535);
FORCEPROP 2 LASTPIN (-6950 775) $PN E9
J 2
(-6960 785);
DISPLAY 0.617021 (-6960 785);
PAINT ORANGE (-6960 785);
FORCEPROP 1 LAST PATH I56
J 0
(-6500 4025);
PAINT GREEN (-6500 4025);
DISPLAY INVISIBLE (-6500 4025);
FORCEPROP 2 LAST CDS_LOCATION J6B1
J 0
(-6900 4075);
DISPLAY 0.617021 (-6900 4075);
PAINT AQUA (-6900 4075);
DISPLAY INVISIBLE (-6900 4075);
FORCEPROP 2 LAST SEC 1
J 0
(-6900 4125);
DISPLAY 0.680851 (-6900 4125);
PAINT MONO (-6900 4125);
DISPLAY INVISIBLE (-6900 4125);
FORCEPROP 2 LAST CDS_LIB mstr_sconn
J 0
(-6550 2075);
PAINT ORANGE (-6550 2075);
DISPLAY INVISIBLE (-6550 2075);
FORCEPROP 2 LAST SEC_TYPE SM
J 0
(-6900 4125);
DISPLAY 1.021277 (-6900 4125);
PAINT ORANGE (-6900 4125);
DISPLAY INVISIBLE (-6900 4125);
FORCEPROP 1 LAST PACK_TYPE SM
J 0
(-6900 4125);
PAINT SKYBLUE (-6900 4125);
DISPLAY INVISIBLE (-6900 4125);
FORCEADD GND..1
(-3975 225);
FORCEPROP 3 LASTPIN (-3975 275) SIG_NAME GND\g
J 0
(-3965 285);
DISPLAY 0.659574 (-3965 285);
PAINT MONO (-3965 285);
DISPLAY INVISIBLE (-3965 285);
FORCEPROP 1 LAST PATH I61
J 0
(-3900 225);
DISPLAY 0.872340 (-3900 225);
PAINT AQUA (-3900 225);
DISPLAY INVISIBLE (-3900 225);
FORCEPROP 1 LAST SIZE 1B
J 0
(-3900 175);
DISPLAY 1.404255 (-3900 175);
PAINT AQUA (-3900 175);
DISPLAY INVISIBLE (-3900 175);
FORCEPROP 2 LAST CDS_LIB mstr_symbols
J 0
(-3975 225);
PAINT MONO (-3975 225);
DISPLAY INVISIBLE (-3975 225);
FORCEPROP 1 LAST VOLTAGE 0.0V
J 0
(-4020 182);
DISPLAY 0.340426 (-4020 182);
PAINT SKYBLUE (-4020 182);
DISPLAY INVISIBLE (-4020 182);
FORCEPROP 1 LAST BODY_TYPE PLUMBING
J 0
(-4020 182);
DISPLAY 0.340426 (-4020 182);
PAINT GREEN (-4020 182);
DISPLAY INVISIBLE (-4020 182);
FORCEPROP 1 LAST HDL_POWER GND
J 0
(-3975 375);
PAINT GREEN (-3975 375);
DISPLAY INVISIBLE (-3975 375);
FORCEADD GND..1
(-2150 200);
FORCEPROP 3 LASTPIN (-2150 250) SIG_NAME GND\g
J 0
(-2140 260);
DISPLAY 0.659574 (-2140 260);
PAINT MONO (-2140 260);
DISPLAY INVISIBLE (-2140 260);
FORCEPROP 1 LAST PATH I62
J 0
(-2075 200);
DISPLAY 0.872340 (-2075 200);
PAINT AQUA (-2075 200);
DISPLAY INVISIBLE (-2075 200);
FORCEPROP 2 LAST CDS_LIB mstr_symbols
J 0
(-2150 200);
PAINT MONO (-2150 200);
DISPLAY INVISIBLE (-2150 200);
FORCEPROP 1 LAST SIZE 1B
J 0
(-2075 150);
DISPLAY 1.404255 (-2075 150);
PAINT AQUA (-2075 150);
DISPLAY INVISIBLE (-2075 150);
FORCEPROP 1 LAST VOLTAGE 0.0V
J 0
(-2195 157);
DISPLAY 0.340426 (-2195 157);
PAINT SKYBLUE (-2195 157);
DISPLAY INVISIBLE (-2195 157);
FORCEPROP 1 LAST BODY_TYPE PLUMBING
J 0
(-2195 157);
DISPLAY 0.340426 (-2195 157);
PAINT GREEN (-2195 157);
DISPLAY INVISIBLE (-2195 157);
FORCEPROP 1 LAST HDL_POWER GND
J 0
(-2150 350);
PAINT GREEN (-2150 350);
DISPLAY INVISIBLE (-2150 350);
FORCEADD OFFPAGE..1
(-4825 2750);
FORCEPROP 2 LAST $XR0 39 
J 0
(-5046 2750);
DISPLAY 0.638298 (-5046 2750);
PAINT MONO (-5046 2750);
FORCEPROP 2 LAST PATH I64
J 0
(-4775 2825);
DISPLAY 1.021277 (-4775 2825);
PAINT ORANGE (-4775 2825);
DISPLAY INVISIBLE (-4775 2825);
FORCEPROP 2 LAST CDS_LIB mstr_standard
J 0
(-4825 2750);
PAINT MONO (-4825 2750);
DISPLAY INVISIBLE (-4825 2750);
FORCEPROP 1 LAST OFFPAGE TRUE
J 0
(-4500 2625);
DISPLAY 1.170213 (-4500 2625);
PAINT GREEN (-4500 2625);
DISPLAY INVISIBLE (-4500 2625);
FORCEPROP 1 LAST COMMENT_BODY TRUE
J 0
(-4700 2650);
DISPLAY 1.170213 (-4700 2650);
PAINT GREEN (-4700 2650);
DISPLAY INVISIBLE (-4700 2650);
FORCEADD OFFPAGE..1
(-4825 2700);
FORCEPROP 2 LAST $XR0 39 
J 0
(-5046 2700);
DISPLAY 0.638298 (-5046 2700);
PAINT MONO (-5046 2700);
FORCEPROP 2 LAST PATH I67
J 0
(-4775 2775);
DISPLAY 1.021277 (-4775 2775);
PAINT ORANGE (-4775 2775);
DISPLAY INVISIBLE (-4775 2775);
FORCEPROP 2 LAST CDS_LIB mstr_standard
J 0
(-4825 2700);
PAINT MONO (-4825 2700);
DISPLAY INVISIBLE (-4825 2700);
FORCEPROP 1 LAST OFFPAGE TRUE
J 0
(-4500 2575);
DISPLAY 1.170213 (-4500 2575);
PAINT GREEN (-4500 2575);
DISPLAY INVISIBLE (-4500 2575);
FORCEPROP 1 LAST COMMENT_BODY TRUE
J 0
(-4700 2600);
DISPLAY 1.170213 (-4700 2600);
PAINT GREEN (-4700 2600);
DISPLAY INVISIBLE (-4700 2600);
FORCEADD VCC_CORE..1
(-5125 3075);
FORCEPROP 3 LASTPIN (-5125 3025) SIG_NAME PVCCMCP_CPU0\g
J 0
(-5115 3035);
DISPLAY 0.659574 (-5115 3035);
PAINT MONO (-5115 3035);
DISPLAY INVISIBLE (-5115 3035);
FORCEPROP 1 LAST HDL_POWER PVCCMCP_CPU0
J 1
(-5125 3125);
DISPLAY 0.617021 (-5125 3125);
PAINT GREEN (-5125 3125);
FORCEPROP 2 LAST BOM_COST PVMCP_FPGA_CPU0_VR
J 0
(-5125 3175);
DISPLAY 2.340426 (-5125 3175);
PAINT WHITE (-5125 3175);
DISPLAY INVISIBLE (-5125 3175);
FORCEPROP 2 LAST CDS_LIB mstr_symbols
J 0
(-5125 3075);
PAINT MONO (-5125 3075);
DISPLAY INVISIBLE (-5125 3075);
FORCEPROP 1 LAST PATH I68
J 0
(-5075 3100);
DISPLAY 0.872340 (-5075 3100);
PAINT AQUA (-5075 3100);
DISPLAY INVISIBLE (-5075 3100);
FORCEPROP 2 LAST ROOM PVMCP_FPGA_CPU0_VR
J 0
(-5125 3175);
DISPLAY 3.127660 (-5125 3175);
PAINT WHITE (-5125 3175);
DISPLAY INVISIBLE (-5125 3175);
FORCEADD VCC_CORE..1
(-2300 3925);
FORCEPROP 3 LASTPIN (-2300 3875) SIG_NAME PVCCMCP_CPU0\g
J 0
(-2290 3885);
DISPLAY 0.659574 (-2290 3885);
PAINT MONO (-2290 3885);
DISPLAY INVISIBLE (-2290 3885);
FORCEPROP 1 LAST HDL_POWER PVCCMCP_CPU0
J 1
(-2300 3975);
DISPLAY 0.617021 (-2300 3975);
PAINT GREEN (-2300 3975);
FORCEPROP 2 LAST ROOM PVMCP_FPGA_CPU0_VR
J 0
(-2300 4025);
DISPLAY 3.127660 (-2300 4025);
PAINT WHITE (-2300 4025);
DISPLAY INVISIBLE (-2300 4025);
FORCEPROP 1 LAST PATH I69
J 0
(-2250 3950);
DISPLAY 0.872340 (-2250 3950);
PAINT AQUA (-2250 3950);
DISPLAY INVISIBLE (-2250 3950);
FORCEPROP 2 LAST CDS_LIB mstr_symbols
J 0
(-2300 3925);
PAINT MONO (-2300 3925);
DISPLAY INVISIBLE (-2300 3925);
FORCEPROP 2 LAST BOM_COST PVMCP_FPGA_CPU0_VR
J 0
(-2300 4025);
DISPLAY 2.340426 (-2300 4025);
PAINT WHITE (-2300 4025);
DISPLAY INVISIBLE (-2300 4025);
FORCEADD CAP_A..1
(-1100 3100);
FORCEPROP 0 LAST GROUP PWR_MCP_CAP
J 0
(-1050 2800);
DISPLAY 0.638298 (-1050 2800);
PAINT BROWN (-1050 2800);
DISPLAY BOTH (-1050 2800);
FORCEPROP 1 LAST LOCATION C3N40
J 0
(-1050 3200);
DISPLAY 0.617021 (-1050 3200);
PAINT AQUA (-1050 3200);
FORCEPROP 1 LAST VALUE 1.0UF
J 0
(-1050 3150);
DISPLAY 0.617021 (-1050 3150);
PAINT SKYBLUE (-1050 3150);
FORCEPROP 1 LAST VOLTAGE 6.3V
J 0
(-1050 3100);
DISPLAY 0.617021 (-1050 3100);
PAINT SKYBLUE (-1050 3100);
FORCEPROP 1 LASTPIN (-1100 3200) $PN 1
J 0
(-1090 3180);
DISPLAY 0.617021 (-1090 3180);
PAINT ORANGE (-1090 3180);
FORCEPROP 1 LASTPIN (-1100 3000) $PN 2
J 0
(-1090 2980);
DISPLAY 0.617021 (-1090 2980);
PAINT ORANGE (-1090 2980);
FORCEPROP 1 LAST TOLERANCE 10%
J 0
(-1050 3050);
DISPLAY 0.617021 (-1050 3050);
PAINT SKYBLUE (-1050 3050);
FORCEPROP 1 LAST MATERIAL X6S
J 0
(-1050 3000);
DISPLAY 0.617021 (-1050 3000);
PAINT SKYBLUE (-1050 3000);
FORCEPROP 1 LAST PART_NUMBER D97712-004
J 0
(-1050 2950);
DISPLAY 0.617021 (-1050 2950);
PAINT BLUE (-1050 2950);
FORCEPROP 1 LAST PACK_TYPE 0402V
J 0
(-1050 2900);
DISPLAY 0.617021 (-1050 2900);
PAINT SKYBLUE (-1050 2900);
FORCEPROP 2 LAST CDS_LIB dev_discrete
J 2
(-1100 3100);
PAINT ORANGE (-1100 3100);
DISPLAY INVISIBLE (-1100 3100);
FORCEPROP 2 LAST CDS_SEC 1
J 2
(-1050 3250);
PAINT ORANGE (-1050 3250);
DISPLAY INVISIBLE (-1050 3250);
FORCEPROP 2 LAST SEC_TYPE 0402V
J 2
(-1050 3300);
DISPLAY 1.021277 (-1050 3300);
PAINT ORANGE (-1050 3300);
DISPLAY INVISIBLE (-1050 3300);
FORCEPROP 2 LAST SEC 1
J 2
(-1050 3300);
DISPLAY 0.680851 (-1050 3300);
PAINT MONO (-1050 3300);
DISPLAY INVISIBLE (-1050 3300);
FORCEPROP 1 LAST PATH I86
J 0
(-1050 3250);
DISPLAY 0.978723 (-1050 3250);
PAINT WHITE (-1050 3250);
DISPLAY INVISIBLE (-1050 3250);
FORCEPROP 2 LAST ROOM P0V95_MCP_CPU0
J 0
(-1050 3250);
DISPLAY 1.659574 (-1050 3250);
PAINT WHITE (-1050 3250);
DISPLAY INVISIBLE (-1050 3250);
FORCEADD CAP_A..1
(-1000 1850);
FORCEPROP 1 LAST MATERIAL X6S
J 0
(-950 1750);
DISPLAY 0.617021 (-950 1750);
PAINT SKYBLUE (-950 1750);
FORCEPROP 1 LAST PART_NUMBER D97712-004
J 0
(-950 1700);
DISPLAY 0.617021 (-950 1700);
PAINT BLUE (-950 1700);
FORCEPROP 0 LAST GROUP PWR_MCP_CAP
J 0
(-950 1550);
DISPLAY 0.638298 (-950 1550);
PAINT BROWN (-950 1550);
DISPLAY BOTH (-950 1550);
FORCEPROP 1 LASTPIN (-1000 1750) $PN 2
J 0
(-990 1730);
DISPLAY 0.617021 (-990 1730);
PAINT ORANGE (-990 1730);
FORCEPROP 1 LASTPIN (-1000 1950) $PN 1
J 0
(-990 1930);
DISPLAY 0.617021 (-990 1930);
PAINT ORANGE (-990 1930);
FORCEPROP 1 LAST VOLTAGE 6.3V
J 0
(-950 1850);
DISPLAY 0.617021 (-950 1850);
PAINT SKYBLUE (-950 1850);
FORCEPROP 1 LAST PACK_TYPE 0402V
J 0
(-950 1650);
DISPLAY 0.617021 (-950 1650);
PAINT SKYBLUE (-950 1650);
FORCEPROP 1 LAST TOLERANCE 10%
J 0
(-950 1800);
DISPLAY 0.617021 (-950 1800);
PAINT SKYBLUE (-950 1800);
FORCEPROP 1 LAST VALUE 1.0UF
J 0
(-950 1900);
DISPLAY 0.617021 (-950 1900);
PAINT SKYBLUE (-950 1900);
FORCEPROP 1 LAST LOCATION C4T2
J 0
(-950 1950);
DISPLAY 0.617021 (-950 1950);
PAINT AQUA (-950 1950);
FORCEPROP 2 LAST ROOM P1V8_MCP_CPU0
J 0
(-950 2000);
DISPLAY 1.659574 (-950 2000);
PAINT WHITE (-950 2000);
DISPLAY INVISIBLE (-950 2000);
FORCEPROP 1 LAST PATH I9
J 0
(-950 2000);
DISPLAY 0.978723 (-950 2000);
PAINT WHITE (-950 2000);
DISPLAY INVISIBLE (-950 2000);
FORCEPROP 2 LAST SEC 1
J 2
(-950 2050);
DISPLAY 0.680851 (-950 2050);
PAINT MONO (-950 2050);
DISPLAY INVISIBLE (-950 2050);
FORCEPROP 2 LAST SEC_TYPE 0402V
J 2
(-950 2050);
DISPLAY 1.021277 (-950 2050);
PAINT ORANGE (-950 2050);
DISPLAY INVISIBLE (-950 2050);
FORCEPROP 2 LAST CDS_SEC 1
J 2
(-950 2000);
PAINT ORANGE (-950 2000);
DISPLAY INVISIBLE (-950 2000);
FORCEPROP 2 LAST CDS_LIB dev_discrete
J 2
(-1000 1850);
PAINT ORANGE (-1000 1850);
DISPLAY INVISIBLE (-1000 1850);
FORCEPROP 2 LAST CDS_LOCATION C4T2
J 0
(-950 1950);
DISPLAY 0.617021 (-950 1950);
PAINT AQUA (-950 1950);
DISPLAY INVISIBLE (-950 1950);
FORCEADD GND..1
(-1400 2825);
FORCEPROP 3 LASTPIN (-1400 2875) SIG_NAME GND\g
J 0
(-1390 2885);
DISPLAY 0.659574 (-1390 2885);
PAINT MONO (-1390 2885);
DISPLAY INVISIBLE (-1390 2885);
FORCEPROP 1 LAST PATH I92
J 0
(-1325 2825);
DISPLAY 0.872340 (-1325 2825);
PAINT AQUA (-1325 2825);
DISPLAY INVISIBLE (-1325 2825);
FORCEPROP 2 LAST CDS_LIB mstr_symbols
J 0
(-1400 2825);
PAINT ORANGE (-1400 2825);
DISPLAY INVISIBLE (-1400 2825);
FORCEPROP 1 LAST SIZE 1B
J 0
(-1325 2775);
DISPLAY 1.404255 (-1325 2775);
PAINT AQUA (-1325 2775);
DISPLAY INVISIBLE (-1325 2775);
FORCEPROP 1 LAST VOLTAGE 0.0V
J 0
(-1445 2782);
DISPLAY 0.340426 (-1445 2782);
PAINT SKYBLUE (-1445 2782);
DISPLAY INVISIBLE (-1445 2782);
FORCEPROP 1 LAST BODY_TYPE PLUMBING
J 0
(-1445 2782);
DISPLAY 0.340426 (-1445 2782);
PAINT GREEN (-1445 2782);
DISPLAY INVISIBLE (-1445 2782);
FORCEPROP 1 LAST HDL_POWER GND
J 0
(-1400 2975);
PAINT GREEN (-1400 2975);
DISPLAY INVISIBLE (-1400 2975);
FORCEADD VCC_CORE..1
(-1400 3325);
FORCEPROP 3 LASTPIN (-1400 3275) SIG_NAME PVCCIOMCP_CPU0\g
J 0
(-1390 3285);
DISPLAY 0.659574 (-1390 3285);
PAINT MONO (-1390 3285);
DISPLAY INVISIBLE (-1390 3285);
FORCEPROP 1 LAST HDL_POWER PVCCIOMCP_CPU0
J 1
(-1400 3375);
DISPLAY 0.617021 (-1400 3375);
PAINT GREEN (-1400 3375);
FORCEPROP 1 LAST PATH I95
J 0
(-1350 3350);
DISPLAY 0.872340 (-1350 3350);
PAINT AQUA (-1350 3350);
DISPLAY INVISIBLE (-1350 3350);
FORCEPROP 2 LAST CDS_LIB mstr_symbols
J 0
(-1400 3325);
PAINT ORANGE (-1400 3325);
DISPLAY INVISIBLE (-1400 3325);
FORCEADD CAP_A..1
(-1400 3100);
FORCEPROP 0 LAST GROUP PWR_MCP_CAP
J 0
(-1350 2850);
DISPLAY 0.638298 (-1350 2850);
PAINT BROWN (-1350 2850);
DISPLAY BOTH (-1350 2850);
FORCEPROP 1 LAST LOCATION C3M46
J 0
(-1350 3200);
DISPLAY 0.617021 (-1350 3200);
PAINT AQUA (-1350 3200);
FORCEPROP 1 LAST PART_NUMBER D97712-004
J 0
(-1350 2950);
DISPLAY 0.617021 (-1350 2950);
PAINT BLUE (-1350 2950);
FORCEPROP 1 LAST PACK_TYPE 0402V
J 0
(-1350 2900);
DISPLAY 0.617021 (-1350 2900);
PAINT SKYBLUE (-1350 2900);
FORCEPROP 1 LAST VOLTAGE 6.3V
J 0
(-1350 3100);
DISPLAY 0.617021 (-1350 3100);
PAINT SKYBLUE (-1350 3100);
FORCEPROP 1 LAST VALUE 1.0UF
J 0
(-1350 3150);
DISPLAY 0.617021 (-1350 3150);
PAINT SKYBLUE (-1350 3150);
FORCEPROP 1 LASTPIN (-1400 3000) $PN 2
J 0
(-1390 2980);
DISPLAY 0.617021 (-1390 2980);
PAINT ORANGE (-1390 2980);
FORCEPROP 1 LASTPIN (-1400 3200) $PN 1
J 0
(-1390 3180);
DISPLAY 0.617021 (-1390 3180);
PAINT ORANGE (-1390 3180);
FORCEPROP 1 LAST MATERIAL X6S
J 0
(-1350 3000);
DISPLAY 0.617021 (-1350 3000);
PAINT SKYBLUE (-1350 3000);
FORCEPROP 1 LAST TOLERANCE 10%
J 0
(-1350 3050);
DISPLAY 0.617021 (-1350 3050);
PAINT SKYBLUE (-1350 3050);
FORCEPROP 2 LAST ROOM P0V95_MCP_CPU0
J 0
(-1350 3250);
DISPLAY 1.659574 (-1350 3250);
PAINT WHITE (-1350 3250);
DISPLAY INVISIBLE (-1350 3250);
FORCEPROP 1 LAST PATH I99
J 0
(-1350 3250);
DISPLAY 0.978723 (-1350 3250);
PAINT WHITE (-1350 3250);
DISPLAY INVISIBLE (-1350 3250);
FORCEPROP 2 LAST SEC 1
J 2
(-1350 3300);
DISPLAY 0.680851 (-1350 3300);
PAINT MONO (-1350 3300);
DISPLAY INVISIBLE (-1350 3300);
FORCEPROP 2 LAST SEC_TYPE 0402V
J 2
(-1350 3300);
DISPLAY 1.021277 (-1350 3300);
PAINT ORANGE (-1350 3300);
DISPLAY INVISIBLE (-1350 3300);
FORCEPROP 2 LAST CDS_SEC 1
J 2
(-1350 3250);
PAINT ORANGE (-1350 3250);
DISPLAY INVISIBLE (-1350 3250);
FORCEPROP 2 LAST CDS_LIB dev_discrete
J 2
(-1400 3100);
PAINT ORANGE (-1400 3100);
DISPLAY INVISIBLE (-1400 3100);
FORCEADD DESIGN_NOTE..1
(-7150 50);
PAINT PURPLE (-7150 50);
FORCEPROP 0 LAST L6 PVCCIOMCP_CPU0:0X04(BUS #2)
J 0
(-7350 -450);
DISPLAY 1.021277 (-7350 -450);
PAINT VIOLET (-7350 -450);
FORCEPROP 0 LAST L7 P1V8_MCP_CPU0: 0X05(BUS #2)
J 0
(-7350 -525);
DISPLAY 1.021277 (-7350 -525);
PAINT VIOLET (-7350 -525);
FORCEPROP 0 LAST L5 PVCCMCP_CPU0: 0X03(BUS #1)
J 0
(-7350 -375);
DISPLAY 1.021277 (-7350 -375);
PAINT VIOLET (-7350 -375);
FORCEPROP 0 LAST L4 SVID ADDRESS
J 0
(-7350 -300);
DISPLAY 1.021277 (-7350 -300);
PAINT VIOLET (-7350 -300);
FORCEPROP 0 LAST L3 PVCCIOMCP_CPU0 & P1V8_MCP_CPU0: 0XC4
J 0
(-7350 -225);
DISPLAY 1.021277 (-7350 -225);
PAINT VIOLET (-7350 -225);
FORCEPROP 0 LAST L2 PVCCMCP_CPU0: 0X98
J 0
(-7350 -150);
DISPLAY 1.021277 (-7350 -150);
PAINT VIOLET (-7350 -150);
FORCEPROP 0 LAST L1 SMBUS ADDRESS
J 0
(-7350 -75);
PAINT VIOLET (-7350 -75);
FORCEPROP 2 LAST ROOM PVCCIN_CPU0_VR
J 0
(-7350 0);
PAINT MONO (-7350 0);
DISPLAY INVISIBLE (-7350 0);
FORCEPROP 2 LAST CDS_LIB mstr_symbols
J 0
(-7150 50);
PAINT MONO (-7150 50);
DISPLAY INVISIBLE (-7150 50);
FORCEPROP 2 LAST BOM_COST SM_CONTROLLER
J 0
(-7350 0);
PAINT MONO (-7350 0);
DISPLAY INVISIBLE (-7350 0);
FORCEPROP 1 LAST COMMENT_BODY TRUE
J 0
(-7125 150);
DISPLAY 1.319149 (-7125 150);
PAINT GREEN (-7125 150);
DISPLAY INVISIBLE (-7125 150);
FORCEADD INTEL_CORP_BPAGE..1
(-400 -625);
FORCEPROP 1 LAST CDS_CON_LAST_MODIFIED Fri Jun 16 17:49:11 2017
J 0
(-1825 -300);
DISPLAY 1.361702 (-1825 -300);
PAINT GREEN (-1825 -300);
DISPLAY INVISIBLE (-1825 -300);
FORCEPROP 1 LAST CUSTOM_TXT_CDS <CURRENT_DESIGN_SHEET> OF <TOTAL_DESIGN_SHEETS>
J 0
(-900 -600);
PAINT ORANGE (-900 -600);
FORCEPROP 2 LAST CUSTOM_TXT_CDS <XR_PAGE_TITLE>
J 0
(-8290 4625);
DISPLAY 0.638298 (-8290 4625);
PAINT PINK (-8290 4625);
DISPLAY INVISIBLE (-8290 4625);
FORCEPROP 2 LAST CUSTOM_TXT_CDS <CON_LAST_MODIFIED>
J 0
(-4400 -550);
DISPLAY 1.361702 (-4400 -550);
PAINT ORANGE (-4400 -550);
FORCEPROP 1 LAST SCH_TITLE MCP CPU0 VRM
J 0
(-8350 -575);
DISPLAY 1.212766 (-8350 -575);
PAINT ORANGE (-8350 -575);
FORCEPROP 2 LAST CDS_LIB mstr_symbols
J 0
(-400 -625);
DISPLAY 1.361702 (-400 -625);
PAINT ORANGE (-400 -625);
DISPLAY INVISIBLE (-400 -625);
FORCEPROP 2 LAST PAGE_BORDER TRUE
J 0
(-8290 4625);
DISPLAY 0.851064 (-8290 4625);
PAINT PINK (-8290 4625);
DISPLAY INVISIBLE (-8290 4625);
FORCEPROP 2 LAST CDS_XR_PAGE_TITLE CR-194 : @BASEBOARD_FAB2_LIB.BASEBOARD_FAB2(SCH_1):PAGE194
J 0
(-8290 4625);
DISPLAY 0.638298 (-8290 4625);
PAINT PINK (-8290 4625);
DISPLAY INVISIBLE (-8290 4625);
FORCEPROP 1 LAST COMMENT_BODY TRUE
J 0
(-388 -613);
DISPLAY 0.617021 (-388 -613);
PAINT GREEN (-388 -613);
DISPLAY INVISIBLE (-388 -613);
WIRE 16 -1 (-1900 3000)(-1900 2975);
WIRE 16 -1 (-1900 3225)(-1900 3200);
WIRE 16 -1 (-7375 1275)(-7375 1425);
WIRE 16 -1 (-7375 1425)(-7375 1475);
WIRE 16 -1 (-6950 1425)(-7375 1425);
WIRE 16 -1 (-7375 1475)(-7375 1525);
WIRE 16 -1 (-6950 1475)(-7375 1475);
WIRE 16 -1 (-7375 1575)(-7375 1525);
WIRE 16 -1 (-6950 1525)(-7375 1525);
WIRE 16 -1 (-7375 1775)(-7375 1575);
WIRE 16 -1 (-6950 1575)(-7375 1575);
WIRE 16 -1 (-7375 1825)(-7375 1775);
WIRE 16 -1 (-6950 1775)(-7375 1775);
WIRE 16 -1 (-7375 1875)(-7375 1825);
WIRE 16 -1 (-6950 1825)(-7375 1825);
WIRE 16 -1 (-7375 1925)(-7375 1875);
WIRE 16 -1 (-6950 1875)(-7375 1875);
WIRE 16 -1 (-7375 2125)(-7375 1925);
WIRE 16 -1 (-6950 1925)(-7375 1925);
WIRE 16 -1 (-7375 2175)(-7375 2125);
WIRE 16 -1 (-6950 2125)(-7375 2125);
WIRE 16 -1 (-7375 2225)(-7375 2175);
WIRE 16 -1 (-6950 2175)(-7375 2175);
WIRE 16 -1 (-7375 2275)(-7375 2225);
WIRE 16 -1 (-6950 2225)(-7375 2225);
WIRE 16 -1 (-7375 2475)(-7375 2275);
WIRE 16 -1 (-6950 2275)(-7375 2275);
WIRE 16 -1 (-7375 2525)(-7375 2475);
WIRE 16 -1 (-6950 2475)(-7375 2475);
WIRE 16 -1 (-7375 2575)(-7375 2525);
WIRE 16 -1 (-6950 2525)(-7375 2525);
WIRE 16 -1 (-7375 2625)(-7375 2575);
WIRE 16 -1 (-6950 2575)(-7375 2575);
WIRE 16 -1 (-7375 2825)(-7375 2625);
WIRE 16 -1 (-6950 2625)(-7375 2625);
WIRE 16 -1 (-7375 2875)(-7375 2825);
WIRE 16 -1 (-6950 2825)(-7375 2825);
WIRE 16 -1 (-7375 2925)(-7375 2875);
WIRE 16 -1 (-6950 2875)(-7375 2875);
WIRE 16 -1 (-7375 2975)(-7375 2925);
WIRE 16 -1 (-6950 2925)(-7375 2925);
WIRE 16 -1 (-7375 3175)(-7375 2975);
WIRE 16 -1 (-6950 2975)(-7375 2975);
WIRE 16 -1 (-7375 3225)(-7375 3175);
WIRE 16 -1 (-6950 3175)(-7375 3175);
WIRE 16 -1 (-7375 3225)(-7375 3275);
WIRE 16 -1 (-6950 3225)(-7375 3225);
WIRE 16 -1 (-7375 3275)(-7375 3325);
WIRE 16 -1 (-6950 3275)(-7375 3275);
WIRE 16 -1 (-7375 3325)(-7375 3675);
WIRE 16 -1 (-6950 3325)(-7375 3325);
WIRE 16 -1 (-6950 3675)(-7375 3675);
WIRE 16 -1 (-7225 725)(-7225 800);
WIRE 16 -1 (-7225 800)(-7075 800);
WIRE 16 -1 (-7075 800)(-7075 775);
WIRE 16 -1 (-7075 825)(-7075 800);
WIRE 16 -1 (-7075 875)(-7075 825);
WIRE 16 -1 (-6950 825)(-7075 825);
WIRE 16 -1 (-7075 775)(-7075 725);
WIRE 16 -1 (-6950 775)(-7075 775);
WIRE 16 -1 (-7075 725)(-7075 625);
WIRE 16 -1 (-6950 725)(-7075 725);
WIRE 16 -1 (-7075 875)(-7075 925);
WIRE 16 -1 (-6950 875)(-7075 875);
WIRE 16 -1 (-7075 925)(-7075 975);
WIRE 16 -1 (-6950 925)(-7075 925);
WIRE 16 -1 (-7075 625)(-7075 575);
WIRE 16 -1 (-6950 625)(-7075 625);
WIRE 16 -1 (-7075 575)(-7075 525);
WIRE 16 -1 (-6950 575)(-7075 575);
WIRE 16 -1 (-7075 975)(-7075 1175);
WIRE 16 -1 (-6950 975)(-7075 975);
WIRE 16 -1 (-7075 1175)(-7075 1225);
WIRE 16 -1 (-6950 1175)(-7075 1175);
WIRE 16 -1 (-7075 525)(-7075 475);
WIRE 16 -1 (-6950 525)(-7075 525);
WIRE 16 -1 (-6950 475)(-7075 475);
WIRE 16 -1 (-6950 1225)(-7075 1225);
WIRE 16 -1 (-7175 3775)(-7175 4025);
WIRE 16 -1 (-7175 3725)(-7175 3775);
WIRE 16 -1 (-6950 3775)(-7175 3775);
WIRE 16 -1 (-7175 3425)(-7175 3725);
WIRE 16 -1 (-6950 3725)(-7175 3725);
WIRE 16 -1 (-7175 3375)(-7175 3425);
WIRE 16 -1 (-6950 3425)(-7175 3425);
WIRE 16 -1 (-7175 3075)(-7175 3375);
WIRE 16 -1 (-6950 3375)(-7175 3375);
WIRE 16 -1 (-7175 3025)(-7175 3075);
WIRE 16 -1 (-6950 3075)(-7175 3075);
WIRE 16 -1 (-7175 2725)(-7175 3025);
WIRE 16 -1 (-6950 3025)(-7175 3025);
WIRE 16 -1 (-7175 2675)(-7175 2725);
WIRE 16 -1 (-6950 2725)(-7175 2725);
WIRE 16 -1 (-7175 2375)(-7175 2675);
WIRE 16 -1 (-6950 2675)(-7175 2675);
WIRE 16 -1 (-7175 2325)(-7175 2375);
WIRE 16 -1 (-6950 2375)(-7175 2375);
WIRE 16 -1 (-7175 2025)(-7175 2325);
WIRE 16 -1 (-6950 2325)(-7175 2325);
WIRE 16 -1 (-7175 1975)(-7175 2025);
WIRE 16 -1 (-6950 2025)(-7175 2025);
WIRE 16 -1 (-7175 1675)(-7175 1975);
WIRE 16 -1 (-6950 1975)(-7175 1975);
WIRE 16 -1 (-7175 1625)(-7175 1675);
WIRE 16 -1 (-6950 1675)(-7175 1675);
WIRE 16 -1 (-7175 1625)(-7175 1325);
WIRE 16 -1 (-6950 1625)(-7175 1625);
WIRE 16 -1 (-7175 1325)(-7175 1275);
WIRE 16 -1 (-7175 1325)(-6950 1325);
WIRE 16 -1 (-7175 1275)(-6950 1275);
WIRE 16 -1 (-5725 3850)(-5725 3775);
WIRE 16 -1 (-5725 3725)(-5725 3775);
WIRE 16 -1 (-5725 3775)(-6150 3775);
WIRE 16 -1 (-5725 3675)(-5725 3725);
WIRE 16 -1 (-6150 3725)(-5725 3725);
WIRE 16 -1 (-6150 3675)(-5725 3675);
WIRE 16 -1 (-5775 3075)(-5775 3150);
WIRE 16 -1 (-5775 3025)(-5775 3075);
WIRE 16 -1 (-6150 3075)(-5775 3075);
WIRE 16 -1 (-5775 2975)(-5775 3025);
WIRE 16 -1 (-6150 3025)(-5775 3025);
WIRE 16 -1 (-6150 2975)(-5775 2975);
WIRE 16 -1 (-5350 1625)(-5350 1575);
WIRE 16 -1 (-5350 1675)(-5350 1625);
WIRE 16 -1 (-6150 1625)(-5350 1625);
WIRE 16 -1 (-6025 1675)(-5350 1675);
WIRE 16 -1 (-6025 1875)(-6025 1675);
WIRE 16 -1 (-6150 1675)(-6025 1675);
WIRE 16 -1 (-6025 1925)(-6025 1875);
WIRE 16 -1 (-6150 1875)(-6025 1875);
WIRE 16 -1 (-6025 1925)(-6025 2225);
WIRE 16 -1 (-6150 1925)(-6025 1925);
WIRE 16 -1 (-6025 2225)(-6025 2275);
WIRE 16 -1 (-6150 2225)(-6025 2225);
WIRE 16 -1 (-6025 2275)(-6025 2475);
WIRE 16 -1 (-6150 2275)(-6025 2275);
WIRE 16 -1 (-6025 2475)(-6025 2525);
WIRE 16 -1 (-6150 2475)(-6025 2475);
WIRE 16 -1 (-6025 2525)(-6025 2575);
WIRE 16 -1 (-6150 2525)(-6025 2525);
WIRE 16 -1 (-6025 2625)(-6025 2575);
WIRE 16 -1 (-6150 2575)(-6025 2575);
WIRE 16 -1 (-6025 2675)(-6025 2625);
WIRE 16 -1 (-6150 2625)(-6025 2625);
WIRE 16 -1 (-6025 2725)(-6025 2675);
WIRE 16 -1 (-6150 2675)(-6025 2675);
WIRE 16 -1 (-6025 2825)(-6025 2725);
WIRE 16 -1 (-6150 2725)(-6025 2725);
WIRE 16 -1 (-6025 2875)(-6025 2825);
WIRE 16 -1 (-6150 2825)(-6025 2825);
WIRE 16 -1 (-6025 2925)(-6025 2875);
WIRE 16 -1 (-6150 2875)(-6025 2875);
WIRE 16 -1 (-6025 2925)(-6025 3175);
WIRE 16 -1 (-6150 2925)(-6025 2925);
WIRE 16 -1 (-6025 3225)(-6025 3175);
WIRE 16 -1 (-6150 3175)(-6025 3175);
WIRE 16 -1 (-6025 3275)(-6025 3225);
WIRE 16 -1 (-6150 3225)(-6025 3225);
WIRE 16 -1 (-6025 3325)(-6025 3275);
WIRE 16 -1 (-6150 3275)(-6025 3275);
WIRE 16 -1 (-6025 3375)(-6025 3325);
WIRE 16 -1 (-6150 3325)(-6025 3325);
WIRE 16 -1 (-6025 3425)(-6025 3375);
WIRE 16 -1 (-6150 3375)(-6025 3375);
WIRE 16 -1 (-6025 3525)(-6025 3425);
WIRE 16 -1 (-6150 3425)(-6025 3425);
WIRE 16 -1 (-6025 3575)(-6025 3525);
WIRE 16 -1 (-6150 3525)(-6025 3525);
WIRE 16 -1 (-6025 3625)(-6025 3575);
WIRE 16 -1 (-6150 3575)(-6025 3575);
WIRE 16 -1 (-6150 3625)(-6025 3625);
WIRE 16 -1 (-3900 3800)(-3900 3875);
WIRE 16 -1 (-3725 3800)(-3900 3800);
WIRE 16 -1 (-3725 3750)(-3725 3800);
WIRE 16 -1 (-3550 3800)(-3725 3800);
WIRE 16 -1 (-3725 3700)(-3725 3750);
WIRE 16 -1 (-3550 3750)(-3725 3750);
WIRE 16 -1 (-3725 3450)(-3725 3700);
WIRE 16 -1 (-3550 3700)(-3725 3700);
WIRE 16 -1 (-3725 3400)(-3725 3450);
WIRE 16 -1 (-3550 3450)(-3725 3450);
WIRE 16 -1 (-3725 3350)(-3725 3400);
WIRE 16 -1 (-3550 3400)(-3725 3400);
WIRE 16 -1 (-3725 3100)(-3725 3350);
WIRE 16 -1 (-3550 3350)(-3725 3350);
WIRE 16 -1 (-3725 3050)(-3725 3100);
WIRE 16 -1 (-3550 3100)(-3725 3100);
WIRE 16 -1 (-3725 3000)(-3725 3050);
WIRE 16 -1 (-3550 3050)(-3725 3050);
WIRE 16 -1 (-3550 3000)(-3725 3000);
WIRE 16 -1 (-4175 4000)(-4175 3750);
WIRE 16 -1 (-3900 3750)(-4175 3750);
WIRE 16 -1 (-3900 3750)(-3900 3600);
WIRE 16 -1 (-3900 3600)(-3900 3550);
WIRE 16 -1 (-3550 3600)(-3900 3600);
WIRE 16 -1 (-3900 3250)(-3900 3550);
WIRE 16 -1 (-3550 3550)(-3900 3550);
WIRE 16 -1 (-3900 3250)(-3900 3200);
WIRE 16 -1 (-3550 3250)(-3900 3250);
WIRE 16 -1 (-3975 3200)(-3900 3200);
WIRE 16 -1 (-3550 3200)(-3900 3200);
WIRE 16 -1 (-3975 2950)(-3975 3200);
WIRE 16 -1 (-3975 2900)(-3975 2950);
WIRE 16 -1 (-3550 2950)(-3975 2950);
WIRE 16 -1 (-3975 2850)(-3975 2900);
WIRE 16 -1 (-3550 2900)(-3975 2900);
WIRE 16 -1 (-3550 2850)(-3975 2850);
WIRE 16 -1 (-1900 2025)(-1900 2000);
WIRE 16 -1 (-1900 2000)(-1600 2000);
WIRE 16 -1 (-1900 1950)(-1900 2000);
WIRE 16 -1 (-1600 2000)(-1600 1950);
WIRE 16 -1 (-1300 2000)(-1300 2025);
WIRE 16 -1 (-1300 2000)(-1000 2000);
WIRE 16 -1 (-1300 1950)(-1300 2000);
WIRE 16 -1 (-1000 2000)(-1000 1950);
WIRE 16 -1 (-5450 2525)(-5450 2175);
WIRE 16 -1 (-5450 2125)(-5450 2175);
WIRE 16 -1 (-6150 2175)(-5450 2175);
WIRE 16 -1 (-5450 2125)(-5450 1825);
WIRE 16 -1 (-6150 2125)(-5450 2125);
WIRE 16 -1 (-5450 1775)(-5450 1825);
WIRE 16 -1 (-6150 1825)(-5450 1825);
WIRE 16 -1 (-5450 1575)(-5450 1775);
WIRE 16 -1 (-6150 1775)(-5450 1775);
WIRE 16 -1 (-5450 1525)(-5450 1575);
WIRE 16 -1 (-6150 1575)(-5450 1575);
WIRE 16 -1 (-5450 1475)(-5450 1525);
WIRE 16 -1 (-6150 1525)(-5450 1525);
WIRE 16 -1 (-5450 1425)(-5450 1475);
WIRE 16 -1 (-6150 1475)(-5450 1475);
WIRE 16 -1 (-5450 1425)(-5450 1225);
WIRE 16 -1 (-6150 1425)(-5450 1425);
WIRE 16 -1 (-5450 1175)(-5450 1225);
WIRE 16 -1 (-6150 1225)(-5450 1225);
WIRE 16 -1 (-5450 1125)(-5450 1175);
WIRE 16 -1 (-6150 1175)(-5450 1175);
WIRE 16 -1 (-5450 1075)(-5450 1125);
WIRE 16 -1 (-6150 1125)(-5450 1125);
WIRE 16 -1 (-5450 875)(-5450 1075);
WIRE 16 -1 (-6150 1075)(-5450 1075);
WIRE 16 -1 (-5450 825)(-5450 875);
WIRE 16 -1 (-6150 875)(-5450 875);
WIRE 16 -1 (-5450 775)(-5450 825);
WIRE 16 -1 (-6150 825)(-5450 825);
WIRE 16 -1 (-5450 725)(-5450 775);
WIRE 16 -1 (-6150 775)(-5450 775);
WIRE 16 -1 (-6150 725)(-5450 725);
WIRE 16 -1 (-1300 1625)(-1300 1650);
WIRE 16 -1 (-1000 1650)(-1300 1650);
WIRE 16 -1 (-1300 1750)(-1300 1650);
WIRE 16 -1 (-1000 1750)(-1000 1650);
WIRE 16 -1 (-7425 3850)(-7425 3525);
WIRE 16 -1 (-7425 3525)(-6950 3525);
WIRE 16 -1 (-7975 -125)(-7975 -175);
WIRE 16 -1 (-8175 -125)(-7975 -125);
WIRE 16 -1 (-7825 -125)(-7975 -125);
WIRE 16 -1 (-7825 0)(-7825 -125);
WIRE 16 -1 (-8175 25)(-8175 -125);
WIRE 16 -1 (-7525 3750)(-7525 3625);
WIRE 16 -1 (-7525 3625)(-6950 3625);
WIRE 16 -1 (-1900 1650)(-1900 1625);
WIRE 16 -1 (-1900 1650)(-1600 1650);
WIRE 16 -1 (-1900 1750)(-1900 1650);
WIRE 16 -1 (-1600 1750)(-1600 1650);
WIRE 16 -1 (-1900 2650)(-1900 2675);
WIRE 16 -1 (-1600 2650)(-1900 2650);
FORCEPROP 0 LAST VOLTAGE 1.2V
J 0
(-1800 2700);
DISPLAY 1.021277 (-1800 2700);
PAINT SKYBLUE (-1800 2700);
DISPLAY INVISIBLE (-1800 2700);
WIRE 16 -1 (-1900 2600)(-1900 2650);
WIRE 16 -1 (-1600 2600)(-1600 2650);
WIRE 16 -1 (-1900 2275)(-1900 2300);
WIRE 16 -1 (-1600 2300)(-1900 2300);
WIRE 16 -1 (-1900 2300)(-1900 2400);
WIRE 16 -1 (-1600 2400)(-1600 2300);
WIRE 16 -1 (-3975 400)(-3975 275);
WIRE 16 -1 (-3975 450)(-3975 400);
WIRE 16 -1 (-3550 400)(-3975 400);
WIRE 16 -1 (-3975 500)(-3975 450);
WIRE 16 -1 (-3550 450)(-3975 450);
WIRE 16 -1 (-3975 750)(-3975 500);
WIRE 16 -1 (-3550 500)(-3975 500);
WIRE 16 -1 (-3975 800)(-3975 750);
WIRE 16 -1 (-3550 750)(-3975 750);
WIRE 16 -1 (-3975 850)(-3975 800);
WIRE 16 -1 (-3550 800)(-3975 800);
WIRE 16 -1 (-3975 1100)(-3975 850);
WIRE 16 -1 (-3550 850)(-3975 850);
WIRE 16 -1 (-3975 1150)(-3975 1100);
WIRE 16 -1 (-3550 1100)(-3975 1100);
WIRE 16 -1 (-3975 1200)(-3975 1150);
WIRE 16 -1 (-3550 1150)(-3975 1150);
WIRE 16 -1 (-3975 1450)(-3975 1200);
WIRE 16 -1 (-3550 1200)(-3975 1200);
WIRE 16 -1 (-3975 1500)(-3975 1450);
WIRE 16 -1 (-3550 1450)(-3975 1450);
WIRE 16 -1 (-3975 1550)(-3975 1500);
WIRE 16 -1 (-3550 1500)(-3975 1500);
WIRE 16 -1 (-3975 1800)(-3975 1550);
WIRE 16 -1 (-3550 1550)(-3975 1550);
WIRE 16 -1 (-3975 1850)(-3975 1800);
WIRE 16 -1 (-3550 1800)(-3975 1800);
WIRE 16 -1 (-3975 1900)(-3975 1850);
WIRE 16 -1 (-3550 1850)(-3975 1850);
WIRE 16 -1 (-3975 1900)(-3975 2250);
WIRE 16 -1 (-3550 1900)(-3975 1900);
WIRE 16 -1 (-3975 2500)(-3975 2250);
WIRE 16 -1 (-3550 2250)(-3975 2250);
WIRE 16 -1 (-3975 2550)(-3975 2500);
WIRE 16 -1 (-3550 2500)(-3975 2500);
WIRE 16 -1 (-3975 2600)(-3975 2550);
WIRE 16 -1 (-3550 2550)(-3975 2550);
WIRE 16 -1 (-3550 2600)(-3975 2600);
WIRE 16 -1 (-2150 400)(-2150 250);
WIRE 16 -1 (-2150 450)(-2150 400);
WIRE 16 -1 (-2750 400)(-2150 400);
WIRE 16 -1 (-2150 500)(-2150 450);
WIRE 16 -1 (-2750 450)(-2150 450);
WIRE 16 -1 (-2150 550)(-2150 500);
WIRE 16 -1 (-2750 500)(-2150 500);
WIRE 16 -1 (-2150 600)(-2150 550);
WIRE 16 -1 (-2750 550)(-2150 550);
WIRE 16 -1 (-2150 650)(-2150 600);
WIRE 16 -1 (-2750 600)(-2150 600);
WIRE 16 -1 (-2150 750)(-2150 650);
WIRE 16 -1 (-2750 650)(-2150 650);
WIRE 16 -1 (-2150 800)(-2150 750);
WIRE 16 -1 (-2750 750)(-2150 750);
WIRE 16 -1 (-2150 850)(-2150 800);
WIRE 16 -1 (-2750 800)(-2150 800);
WIRE 16 -1 (-2150 900)(-2150 850);
WIRE 16 -1 (-2750 850)(-2150 850);
WIRE 16 -1 (-2150 950)(-2150 900);
WIRE 16 -1 (-2750 900)(-2150 900);
WIRE 16 -1 (-2150 1000)(-2150 950);
WIRE 16 -1 (-2750 950)(-2150 950);
WIRE 16 -1 (-2150 1100)(-2150 1000);
WIRE 16 -1 (-2750 1000)(-2150 1000);
WIRE 16 -1 (-2150 1150)(-2150 1100);
WIRE 16 -1 (-2750 1100)(-2150 1100);
WIRE 16 -1 (-2150 1200)(-2150 1150);
WIRE 16 -1 (-2750 1150)(-2150 1150);
WIRE 16 -1 (-2150 1200)(-2150 1450);
WIRE 16 -1 (-2750 1200)(-2150 1200);
WIRE 16 -1 (-2150 1500)(-2150 1450);
WIRE 16 -1 (-2750 1450)(-2150 1450);
WIRE 16 -1 (-2150 1550)(-2150 1500);
WIRE 16 -1 (-2750 1500)(-2150 1500);
WIRE 16 -1 (-2150 1800)(-2150 1550);
WIRE 16 -1 (-2750 1550)(-2150 1550);
WIRE 16 -1 (-2150 1850)(-2150 1800);
WIRE 16 -1 (-2750 1800)(-2150 1800);
WIRE 16 -1 (-2150 1900)(-2150 1850);
WIRE 16 -1 (-2750 1850)(-2150 1850);
WIRE 16 -1 (-2150 2150)(-2150 1900);
WIRE 16 -1 (-2750 1900)(-2150 1900);
WIRE 16 -1 (-2150 2200)(-2150 2150);
WIRE 16 -1 (-2750 2150)(-2150 2150);
WIRE 16 -1 (-2150 2250)(-2150 2200);
WIRE 16 -1 (-2750 2200)(-2150 2200);
WIRE 16 -1 (-2150 2500)(-2150 2250);
WIRE 16 -1 (-2750 2250)(-2150 2250);
WIRE 16 -1 (-2150 2550)(-2150 2500);
WIRE 16 -1 (-2750 2500)(-2150 2500);
WIRE 16 -1 (-2150 2600)(-2150 2550);
WIRE 16 -1 (-2750 2550)(-2150 2550);
WIRE 16 -1 (-2150 2850)(-2150 2600);
WIRE 16 -1 (-2750 2600)(-2150 2600);
WIRE 16 -1 (-2150 2900)(-2150 2850);
WIRE 16 -1 (-2750 2850)(-2150 2850);
WIRE 16 -1 (-2150 2950)(-2150 2900);
WIRE 16 -1 (-2750 2900)(-2150 2900);
WIRE 16 -1 (-2150 3200)(-2150 2950);
WIRE 16 -1 (-2750 2950)(-2150 2950);
WIRE 16 -1 (-2150 3250)(-2150 3200);
WIRE 16 -1 (-2750 3200)(-2150 3200);
WIRE 16 -1 (-2150 3300)(-2150 3250);
WIRE 16 -1 (-2750 3250)(-2150 3250);
WIRE 16 -1 (-2150 3550)(-2150 3300);
WIRE 16 -1 (-2750 3300)(-2150 3300);
WIRE 16 -1 (-2150 3600)(-2150 3550);
WIRE 16 -1 (-2750 3550)(-2150 3550);
WIRE 16 -1 (-2150 3650)(-2150 3600);
WIRE 16 -1 (-2750 3600)(-2150 3600);
WIRE 16 -1 (-2750 3650)(-2150 3650);
WIRE 16 -1 (-5125 3025)(-5125 2650);
WIRE 16 -1 (-5125 2650)(-3725 2650);
WIRE 16 -1 (-3725 2400)(-3725 2650);
WIRE 16 -1 (-3550 2650)(-3725 2650);
WIRE 16 -1 (-3725 2350)(-3725 2400);
WIRE 16 -1 (-3550 2400)(-3725 2400);
WIRE 16 -1 (-3725 2300)(-3725 2350);
WIRE 16 -1 (-3550 2350)(-3725 2350);
WIRE 16 -1 (-3725 2050)(-3725 2300);
WIRE 16 -1 (-3550 2300)(-3725 2300);
WIRE 16 -1 (-3725 2000)(-3725 2050);
WIRE 16 -1 (-3550 2050)(-3725 2050);
WIRE 16 -1 (-3725 1950)(-3725 2000);
WIRE 16 -1 (-3550 2000)(-3725 2000);
WIRE 16 -1 (-3725 1700)(-3725 1950);
WIRE 16 -1 (-3550 1950)(-3725 1950);
WIRE 16 -1 (-3725 1650)(-3725 1700);
WIRE 16 -1 (-3550 1700)(-3725 1700);
WIRE 16 -1 (-3725 1600)(-3725 1650);
WIRE 16 -1 (-3550 1650)(-3725 1650);
WIRE 16 -1 (-3725 1350)(-3725 1600);
WIRE 16 -1 (-3550 1600)(-3725 1600);
WIRE 16 -1 (-3725 1300)(-3725 1350);
WIRE 16 -1 (-3550 1350)(-3725 1350);
WIRE 16 -1 (-3725 1250)(-3725 1300);
WIRE 16 -1 (-3550 1300)(-3725 1300);
WIRE 16 -1 (-3725 1000)(-3725 1250);
WIRE 16 -1 (-3550 1250)(-3725 1250);
WIRE 16 -1 (-3725 950)(-3725 1000);
WIRE 16 -1 (-3550 1000)(-3725 1000);
WIRE 16 -1 (-3725 900)(-3725 950);
WIRE 16 -1 (-3550 950)(-3725 950);
WIRE 16 -1 (-3725 650)(-3725 900);
WIRE 16 -1 (-3550 900)(-3725 900);
WIRE 16 -1 (-3725 600)(-3725 650);
WIRE 16 -1 (-3550 650)(-3725 650);
WIRE 16 -1 (-3725 550)(-3725 600);
WIRE 16 -1 (-3550 600)(-3725 600);
WIRE 16 -1 (-3550 550)(-3725 550);
WIRE 16 -1 (-2300 3800)(-2300 3875);
WIRE 16 -1 (-2300 3750)(-2300 3800);
WIRE 16 -1 (-2750 3800)(-2300 3800);
WIRE 16 -1 (-2300 3700)(-2300 3750);
WIRE 16 -1 (-2750 3750)(-2300 3750);
WIRE 16 -1 (-2300 3450)(-2300 3700);
WIRE 16 -1 (-2750 3700)(-2300 3700);
WIRE 16 -1 (-2300 3400)(-2300 3450);
WIRE 16 -1 (-2750 3450)(-2300 3450);
WIRE 16 -1 (-2300 3350)(-2300 3400);
WIRE 16 -1 (-2750 3400)(-2300 3400);
WIRE 16 -1 (-2300 3100)(-2300 3350);
WIRE 16 -1 (-2750 3350)(-2300 3350);
WIRE 16 -1 (-2300 3050)(-2300 3100);
WIRE 16 -1 (-2750 3100)(-2300 3100);
WIRE 16 -1 (-2300 3000)(-2300 3050);
WIRE 16 -1 (-2750 3050)(-2300 3050);
WIRE 16 -1 (-2300 2750)(-2300 3000);
WIRE 16 -1 (-2750 3000)(-2300 3000);
WIRE 16 -1 (-2300 2700)(-2300 2750);
WIRE 16 -1 (-2750 2750)(-2300 2750);
WIRE 16 -1 (-2300 2650)(-2300 2700);
WIRE 16 -1 (-2750 2700)(-2300 2700);
WIRE 16 -1 (-2300 2400)(-2300 2650);
WIRE 16 -1 (-2750 2650)(-2300 2650);
WIRE 16 -1 (-2300 2350)(-2300 2400);
WIRE 16 -1 (-2750 2400)(-2300 2400);
WIRE 16 -1 (-2300 2300)(-2300 2350);
WIRE 16 -1 (-2750 2350)(-2300 2350);
WIRE 16 -1 (-2300 2050)(-2300 2300);
WIRE 16 -1 (-2750 2300)(-2300 2300);
WIRE 16 -1 (-2300 2000)(-2300 2050);
WIRE 16 -1 (-2750 2050)(-2300 2050);
WIRE 16 -1 (-2300 1950)(-2300 2000);
WIRE 16 -1 (-2750 2000)(-2300 2000);
WIRE 16 -1 (-2300 1700)(-2300 1950);
WIRE 16 -1 (-2750 1950)(-2300 1950);
WIRE 16 -1 (-2300 1650)(-2300 1700);
WIRE 16 -1 (-2750 1700)(-2300 1700);
WIRE 16 -1 (-2300 1600)(-2300 1650);
WIRE 16 -1 (-2750 1650)(-2300 1650);
WIRE 16 -1 (-2300 1600)(-2300 1350);
WIRE 16 -1 (-2750 1600)(-2300 1600);
WIRE 16 -1 (-2300 1350)(-2300 1300);
WIRE 16 -1 (-2750 1350)(-2300 1350);
WIRE 16 -1 (-2300 1300)(-2300 1250);
WIRE 16 -1 (-2750 1300)(-2300 1300);
WIRE 16 -1 (-2300 1250)(-2750 1250);
WIRE 16 -1 (-1400 2875)(-1400 2900);
WIRE 16 -1 (-1100 2900)(-1400 2900);
WIRE 16 -1 (-1400 2900)(-1400 3000);
WIRE 16 -1 (-1100 3000)(-1100 2900);
WIRE 16 -1 (-1400 3250)(-1400 3275);
WIRE 16 -1 (-1100 3250)(-1400 3250);
WIRE 16 -1 (-1400 3200)(-1400 3250);
WIRE 16 -1 (-1100 3200)(-1100 3250);
WIRE 16 -1 (-6150 2375)(-5400 2375);
FORCEPROP 2 LAST SIG_NAME FM_P1V8MCP_CPU0_EN
J 0
(-6000 2385);
DISPLAY 0.617021 (-6000 2385);
PAINT ORANGE (-6000 2385);
WIRE 16 -1 (-6150 375)(-5375 375);
FORCEPROP 2 LAST SIG_NAME SVID_DIO1_CPU0_R
J 0
(-6000 385);
DISPLAY 0.617021 (-6000 385);
PAINT ORANGE (-6000 385);
WIRE 16 -1 (-8075 3575)(-6950 3575);
FORCEPROP 2 LAST SIG_NAME FM_CPU0_VRM_322M_156M_OSC_EN
J 0
(-8050 3585);
DISPLAY 0.617021 (-8050 3585);
PAINT ORANGE (-8050 3585);
WIRE 16 -1 (-7950 1075)(-6950 1075);
FORCEPROP 2 LAST SIG_NAME VSENSE_PVCCIOMCP_CPU0_SKT_VRTN
J 0
(-7960 1085);
DISPLAY 0.617021 (-7960 1085);
PAINT ORANGE (-7960 1085);
WIRE 16 -1 (-7950 1125)(-6950 1125);
FORCEPROP 2 LAST SIG_NAME VSENSE_PVCCIOMCP_CPU0_SKT_VSEN
J 0
(-7960 1135);
DISPLAY 0.617021 (-7960 1135);
PAINT ORANGE (-7960 1135);
WIRE 16 -1 (-4050 3475)(-4950 3475);
FORCEPROP 2 LAST SIG_NAME VSENSE_P1V8MCP_CPU0_SKT_VRTN
J 0
(-4940 3495);
DISPLAY 0.617021 (-4940 3495);
PAINT ORANGE (-4940 3495);
WIRE 16 -1 (-4050 3300)(-4050 3475);
WIRE 16 -1 (-3550 3300)(-4050 3300);
WIRE 16 -1 (-3550 3650)(-4050 3650);
WIRE 16 -1 (-4050 3650)(-4050 3550);
WIRE 16 -1 (-4950 3550)(-4050 3550);
FORCEPROP 2 LAST SIG_NAME VSENSE_P1V8MCP_CPU0_SKT_VSEN
J 0
(-4965 3570);
DISPLAY 0.617021 (-4965 3570);
PAINT ORANGE (-4965 3570);
WIRE 3 682 (-3900 2800)(-4050 2800);
WIRE 3 682 (-3900 3000)(-3900 2800);
WIRE 3 682 (-4050 2800)(-4050 3000);
WIRE 3 682 (-4050 3000)(-3900 3000);
WIRE 16 -1 (-4775 2750)(-3550 2750);
FORCEPROP 2 LAST SIG_NAME VSENSE_PVCCMCP_CPU0_SKT_VSEN
J 0
(-4790 2770);
DISPLAY 0.617021 (-4790 2770);
PAINT ORANGE (-4790 2770);
WIRE 16 -1 (-3550 2200)(-4800 2200);
FORCEPROP 2 LAST SIG_NAME CLK_322M_156M_CPU0_OSC_VRM_DP
J 0
(-4760 2210);
DISPLAY 0.617021 (-4760 2210);
PAINT ORANGE (-4760 2210);
WIRE 3 682 (-6050 1900)(-6050 1850);
WIRE 3 682 (-6000 1900)(-6050 1900);
WIRE 3 682 (-6050 1850)(-6000 1850);
WIRE 3 682 (-6000 1850)(-6000 1900);
WIRE 16 -1 (-6150 2025)(-5425 2025);
FORCEPROP 2 LAST SIG_NAME FM_PVCCIOMCP_CPU0_EN
J 0
(-5975 2035);
DISPLAY 0.617021 (-5975 2035);
PAINT ORANGE (-5975 2035);
WIRE 16 -1 (-6150 1975)(-5400 1975);
FORCEPROP 2 LAST SIG_NAME PWRGD_PVCCIOMCP_CPU0
J 0
(-5990 1990);
DISPLAY 0.617021 (-5990 1990);
PAINT ORANGE (-5990 1990);
WIRE 3 682 (-6050 2250)(-6050 2200);
WIRE 3 682 (-6000 2250)(-6050 2250);
WIRE 3 682 (-6050 2200)(-6000 2200);
WIRE 3 682 (-6000 2200)(-6000 2250);
WIRE 16 -1 (-6150 2325)(-5400 2325);
FORCEPROP 2 LAST SIG_NAME PWRGD_P1V8MCP_CPU0
J 0
(-5990 2340);
DISPLAY 0.617021 (-5990 2340);
PAINT ORANGE (-5990 2340);
WIRE 16 -1 (-6150 1325)(-5350 1325);
FORCEPROP 2 LAST SIG_NAME SMB_VR_STBY_LVC3_SCL
J 0
(-6040 1340);
DISPLAY 0.617021 (-6040 1340);
PAINT ORANGE (-6040 1340);
WIRE 16 -1 (-4775 2700)(-3550 2700);
FORCEPROP 2 LAST SIG_NAME VSENSE_PVCCMCP_CPU0_SKT_VRTN
J 0
(-4790 2720);
DISPLAY 0.617021 (-4790 2720);
PAINT ORANGE (-4790 2720);
WIRE 16 -1 (-3550 2150)(-4825 2150);
FORCEPROP 2 LAST SIG_NAME CLK_322M_156M_CPU0_OSC_VRM_DN
J 0
(-4785 2160);
DISPLAY 0.617021 (-4785 2160);
PAINT ORANGE (-4785 2160);
WIRE 3 682 (-2100 3450)(-2100 1500);
WIRE 3 682 (-450 3450)(-2100 3450);
WIRE 3 682 (-2100 1500)(-450 1500);
WIRE 3 682 (-450 1500)(-450 3450);
WIRE 16 -1 (-6150 575)(-5325 575);
FORCEPROP 2 LAST SIG_NAME SVID_DIO0_CPU0_R
J 0
(-6000 585);
DISPLAY 0.617021 (-6000 585);
PAINT ORANGE (-6000 585);
WIRE 16 -1 (-6150 975)(-5300 975);
FORCEPROP 2 LAST SIG_NAME SVID_ALERT0_CPU0_R_N
J 0
(-6025 985);
DISPLAY 0.617021 (-6025 985);
PAINT ORANGE (-6025 985);
WIRE 16 -1 (-6150 925)(-5300 925);
FORCEPROP 2 LAST SIG_NAME SVID_ALERT1_CPU0_R_N
J 0
(-6025 935);
DISPLAY 0.617021 (-6025 935);
PAINT ORANGE (-6025 935);
WIRE 16 -1 (-6150 1275)(-5350 1275);
FORCEPROP 2 LAST SIG_NAME SMB_VR_STBY_LVC3_SDA
J 0
(-6040 1290);
DISPLAY 0.617021 (-6040 1290);
PAINT ORANGE (-6040 1290);
WIRE 16 -1 (-6150 425)(-5375 425);
FORCEPROP 0 LAST SIG_NAME SVID_CLK1_CPU0_R
J 0
(-6000 435);
DISPLAY 0.617021 (-6000 435);
PAINT ORANGE (-6000 435);
WIRE 16 -1 (-6150 475)(-5350 475);
FORCEPROP 2 LAST SIG_NAME PWRGD_PVCCMCP_CPU0
J 0
(-5990 490);
DISPLAY 0.617021 (-5990 490);
PAINT ORANGE (-5990 490);
WIRE 16 -1 (-6150 525)(-5350 525);
FORCEPROP 2 LAST SIG_NAME FM_PVCCMCP_CPU0_EN
J 0
(-6000 535);
DISPLAY 0.617021 (-6000 535);
PAINT ORANGE (-6000 535);
WIRE 16 -1 (-6150 625)(-5325 625);
FORCEPROP 0 LAST SIG_NAME SVID_CLK0_CPU0_R
J 0
(-6000 635);
DISPLAY 0.617021 (-6000 635);
PAINT ORANGE (-6000 635);
WIRE 16 -1 (-8175 225)(-8175 425);
WIRE 16 -1 (-6950 425)(-8175 425);
FORCEPROP 2 LAST SIG_NAME VR_PVCCIOMCP_CPU0_XADDR1
J 0
(-7715 440);
DISPLAY 0.617021 (-7715 440);
PAINT ORANGE (-7715 440);
FORCEPROP 2 LASTPROP $XRERR UNIQUE?
J 0
(-7955 440);
DISPLAY 0.638298 (-7955 440);
PAINT MONO (-7955 440);
DISPLAY INVISIBLE (-7955 440);
WIRE 3 682 (-7500 -225)(-8250 -225);
WIRE 3 682 (-7500 300)(-7500 -225);
WIRE 3 682 (-8250 -225)(-8250 300);
WIRE 3 682 (-8250 300)(-7500 300);
WIRE 16 -1 (-7825 375)(-7825 200);
WIRE 16 -1 (-7825 375)(-6950 375);
FORCEPROP 2 LAST SIG_NAME VR_PVCCMCP_CPU0_XADDR2
J 0
(-7715 390);
DISPLAY 0.617021 (-7715 390);
PAINT ORANGE (-7715 390);
FORCEPROP 2 LASTPROP $XRERR UNIQUE?
J 0
(-7955 390);
DISPLAY 0.638298 (-7955 390);
PAINT MONO (-7955 390);
DISPLAY INVISIBLE (-7955 390);
DOT 1 (-1900 1650);
DOT 1 (-1900 2000);
DOT 1 (-1300 1650);
DOT 1 (-1300 2000);
DOT 1 (-2300 1650);
DOT 1 (-2300 1700);
DOT 1 (-1900 2300);
DOT 1 (-1900 2650);
DOT 1 (-1400 2900);
DOT 1 (-1400 3250);
DOT 1 (-2150 2900);
DOT 1 (-2150 2850);
DOT 1 (-2300 3700);
DOT 1 (-2300 3750);
DOT 1 (-2150 3300);
DOT 1 (-2150 3250);
DOT 1 (-2150 3200);
DOT 1 (-2150 650);
DOT 1 (-2300 1350);
DOT 1 (-2300 3100);
DOT 1 (-2300 3050);
DOT 1 (-2150 2950);
DOT 1 (-5350 1625);
DOT 1 (-2300 1950);
DOT 1 (-7375 2875);
DOT 1 (-6025 3325);
DOT 1 (-5450 1775);
DOT 1 (-6025 2725);
DOT 1 (-6025 2275);
DOT 1 (-6025 2225);
DOT 1 (-6025 2475);
DOT 1 (-6025 2525);
DOT 1 (-6025 2575);
DOT 1 (-6025 1875);
DOT 1 (-7175 2025);
DOT 1 (-7375 2175);
DOT 1 (-7375 2225);
DOT 1 (-7375 2575);
DOT 1 (-6025 2825);
DOT 1 (-2300 3400);
DOT 1 (-3975 2950);
DOT 1 (-2150 3600);
DOT 1 (-2150 3550);
DOT 1 (-2300 3450);
DOT 1 (-3725 2350);
DOT 1 (-3725 2300);
DOT 1 (-3900 3600);
DOT 1 (-3900 3550);
DOT 1 (-3900 3250);
DOT 1 (-3975 2900);
DOT 1 (-3900 3200);
DOT 1 (-3725 3050);
DOT 1 (-3725 3100);
DOT 1 (-3725 3800);
DOT 1 (-3725 3450);
DOT 1 (-3725 3400);
DOT 1 (-3975 2550);
DOT 1 (-2300 3000);
DOT 1 (-3975 1200);
DOT 1 (-2300 2650);
DOT 1 (-2300 2700);
DOT 1 (-2300 2750);
DOT 1 (-2150 600);
DOT 1 (-2150 550);
DOT 1 (-2150 500);
DOT 1 (-2150 400);
DOT 1 (-2150 450);
DOT 1 (-2150 750);
DOT 1 (-2300 1300);
DOT 1 (-3975 1450);
DOT 1 (-7975 -125);
DOT 1 (-5725 3775);
DOT 1 (-5725 3725);
DOT 1 (-6025 3525);
DOT 1 (-6025 3425);
DOT 1 (-6025 3375);
DOT 1 (-6025 3175);
DOT 1 (-5775 3075);
DOT 1 (-5450 2125);
DOT 1 (-5775 3025);
DOT 1 (-6025 2875);
DOT 1 (-6025 2925);
DOT 1 (-6025 2625);
DOT 1 (-6025 2675);
DOT 1 (-5450 1825);
DOT 1 (-5450 1575);
DOT 1 (-5450 1475);
DOT 1 (-5450 1425);
DOT 1 (-5450 1175);
DOT 1 (-5450 1225);
DOT 1 (-5450 1125);
DOT 1 (-5450 1075);
DOT 1 (-6025 1925);
DOT 1 (-5450 825);
DOT 1 (-5450 775);
DOT 1 (-7175 3725);
DOT 1 (-7175 3775);
DOT 1 (-7175 3425);
DOT 1 (-7175 3375);
DOT 1 (-7375 3225);
DOT 1 (-7375 3175);
DOT 1 (-7175 3075);
DOT 1 (-7175 3025);
DOT 1 (-7375 2975);
DOT 1 (-7375 2925);
DOT 1 (-7375 2825);
DOT 1 (-7175 2675);
DOT 1 (-7175 2725);
DOT 1 (-7375 2625);
DOT 1 (-7175 2325);
DOT 1 (-7375 2475);
DOT 1 (-7375 2525);
DOT 1 (-7375 2275);
DOT 1 (-7375 2125);
DOT 1 (-7075 1175);
DOT 1 (-7075 975);
DOT 1 (-7075 925);
DOT 1 (-7075 875);
DOT 1 (-7075 775);
DOT 1 (-7075 525);
DOT 1 (-7175 1975);
DOT 1 (-7375 1925);
DOT 1 (-7375 1875);
DOT 1 (-7375 1825);
DOT 1 (-7175 1625);
DOT 1 (-7175 1675);
DOT 1 (-7375 1575);
DOT 1 (-7375 1775);
DOT 1 (-7175 1325);
DOT 1 (-7375 1525);
DOT 1 (-7375 1475);
DOT 1 (-7375 1425);
DOT 1 (-6025 3575);
DOT 1 (-2300 3800);
DOT 1 (-2300 3350);
DOT 1 (-2150 2600);
DOT 1 (-2150 2500);
DOT 1 (-2150 2550);
DOT 1 (-2150 2250);
DOT 1 (-2300 2350);
DOT 1 (-2300 2400);
DOT 1 (-2300 2300);
DOT 1 (-3725 3750);
DOT 1 (-3725 3700);
DOT 1 (-3725 3350);
DOT 1 (-3725 2650);
DOT 1 (-3975 2500);
DOT 1 (-2150 2200);
DOT 1 (-2150 2150);
DOT 1 (-2300 2050);
DOT 1 (-2300 2000);
DOT 1 (-2150 1850);
DOT 1 (-2150 1900);
DOT 1 (-2150 1800);
DOT 1 (-2150 1550);
DOT 1 (-2150 1500);
DOT 1 (-2150 1450);
DOT 1 (-2150 1200);
DOT 1 (-2150 1150);
DOT 1 (-2150 1100);
DOT 1 (-2150 1000);
DOT 1 (-2150 950);
DOT 1 (-2150 900);
DOT 1 (-2150 850);
DOT 1 (-2150 800);
DOT 1 (-3725 1700);
DOT 1 (-3725 1650);
DOT 1 (-3725 1600);
DOT 1 (-3725 1350);
DOT 1 (-3725 1300);
DOT 1 (-3725 1250);
DOT 1 (-3975 1550);
DOT 1 (-3975 1500);
DOT 1 (-3725 950);
DOT 1 (-3725 900);
DOT 1 (-3975 1150);
DOT 1 (-3975 1100);
DOT 1 (-3975 850);
DOT 1 (-3975 800);
DOT 1 (-3975 750);
DOT 1 (-3725 600);
DOT 1 (-3725 650);
DOT 1 (-3975 500);
DOT 1 (-3975 450);
DOT 1 (-3975 400);
DOT 1 (-7175 2375);
DOT 1 (-7375 3325);
DOT 1 (-7375 3275);
DOT 1 (-7075 725);
DOT 1 (-7075 575);
DOT 1 (-7075 825);
DOT 1 (-7075 800);
DOT 1 (-6025 1675);
DOT 1 (-5450 2175);
DOT 1 (-3975 1800);
DOT 1 (-3975 1900);
DOT 1 (-3975 1850);
DOT 1 (-3725 1950);
DOT 1 (-3725 2000);
DOT 1 (-3725 2050);
DOT 1 (-3975 2250);
DOT 1 (-3725 2400);
DOT 1 (-2300 1600);
DOT 1 (-6025 3275);
DOT 1 (-6025 3225);
DOT 1 (-5450 875);
DOT 1 (-3725 1000);
DOT 1 (-5450 1525);
DOT 1 (-7075 625);
FORCENOTE
TP FAB4 ADD ATTRIBUTE GROUP=PWR_MCP_CAP 20170508
(-2100 1450) 0;
DISPLAY LEFT (-2100 1450);
DISPLAY 0.638298 (-2100 1450);
PAINT RED (-2100 1450);
FORCENOTE
DEBUG ONLY
(-5927 4081) 0;
DISPLAY LEFT (-5927 4081);
DISPLAY 3.936170 (-5927 4081);
PAINT PURPLE (-5927 4081);
FORCENOTE
TP FAB1 CHANGE CONNECTION 0318
(-5975 1850) 0;
DISPLAY LEFT (-5975 1850);
DISPLAY 1.021277 (-5975 1850);
PAINT RED (-5975 1850);
FORCENOTE
TP FAB1 CHANGE CONNECTION 0318
(-6000 2225) 0;
DISPLAY LEFT (-6000 2225);
DISPLAY 1.021277 (-6000 2225);
PAINT RED (-6000 2225);
FORCENOTE
TP FAB1 CHANGE CONNECTION 0318
(-5050 3025) 0;
DISPLAY LEFT (-5050 3025);
DISPLAY 1.021277 (-5050 3025);
PAINT RED (-5050 3025);
FORCENOTE
TP FAB4 ADD ATTRIBUTE GROUP=MCP 20170508
(-8200 -275) 0;
DISPLAY LEFT (-8200 -275);
DISPLAY 0.510638 (-8200 -275);
PAINT RED (-8200 -275);
FORCENOTE
TP FAB4 ADD ATTRIBUTE GROUP=MCP 20170508
(-6900 125) 0;
DISPLAY LEFT (-6900 125);
DISPLAY 0.638298 (-6900 125);
PAINT RED (-6900 125);
FORCENOTE
TP FAB4 ADD ATTRIBUTE GROUP=MCP 20170508
(-3500 150) 0;
DISPLAY LEFT (-3500 150);
DISPLAY 0.510638 (-3500 150);
PAINT RED (-3500 150);
QUIT
